G04 ================== begin FILE IDENTIFICATION RECORD ==================*
G04 Layout Name:  DAT6MTH3AD0_t6m_cm_d_brd_103112_274.brd*
G04 Film Name:    in2*
G04 File Format:  Gerber RS274X*
G04 File Origin:  Cadence Allegro 16.3-S048*
G04 Origin Date:  Tue Nov 26 10:18:24 2013*
G04 *
G04 Layer:  VIA CLASS/IN2*
G04 Layer:  PIN/IN2*
G04 Layer:  MANUFACTURING/PHOTOPLOT_OUTLINE*
G04 Layer:  ETCH/IN2*
G04 Layer:  DRAWING FORMAT/TITLE_BLOCK*
G04 Layer:  DRAWING FORMAT/TITLE_DATA_IN2*
G04 *
G04 Offset:    (0.00 0.00)*
G04 Mirror:    No*
G04 Mode:      Positive*
G04 Rotation:  0*
G04 FullContactRelief:  No*
G04 UndefLineWidth:     6.00*
G04 ================== end FILE IDENTIFICATION RECORD ====================*
%FSLAX25Y25*MOIN*%
%IR0*IPPOS*OFA0.00000B0.00000*MIA0B0*SFA1.00000B1.00000*%
%ADD10C,.02*%
%ADD15C,.06*%
%ADD14C,.052*%
%ADD13C,.066*%
%ADD12C,.0193*%
%ADD16C,.068*%
%ADD11C,.077*%
%ADD17C,.01*%
%ADD18C,.04*%
%ADD19C,.004*%
%ADD20C,.006*%
%ADD21C,.0045*%
%ADD23C,.03004*%
%ADD28C,.03006*%
%ADD35C,.05204*%
%ADD24C,.07004*%
%ADD30C,.02804*%
%ADD29C,.03192*%
%ADD32C,.02734*%
%ADD34C,.08604*%
%ADD31C,.02934*%
%ADD26C,.08704*%
%ADD25C,.07804*%
%ADD33C,.07907*%
%ADD27C,.15206*%
%ADD22C,.15806*%
G75*
%LPD*%
G75*
G36*
G01X296927Y53529D02*
G03X294193I-1367J-622D01*
G02X293738Y53236I-455J207D01*
G01X277521D01*
G02X277082Y53495I-1J500D01*
G03X274427Y52092I-1316J-723D01*
G01X274481Y51985D01*
Y51456D01*
X272900Y49875D01*
Y44743D01*
X275730Y41913D01*
Y39797D01*
G02X275230Y39297I-500J0D01*
G01X270827D01*
G02X269846Y40491I0J1000D01*
G03X267774Y42160I-1474J291D01*
G03X267434Y41955I599J-1378D01*
G02X266810I-312J391D01*
G03X266470Y42160I-939J-1173D01*
G03X264398Y40491I-598J-1378D01*
G02X263417Y39297I-981J-194D01*
G01X257754D01*
X255884Y41167D01*
X200428D01*
X198138Y43457D01*
X164100D01*
X163671Y43709D01*
X163607Y43807D01*
G03X161037Y43714I-1257J-823D01*
G01Y43713D01*
G02X160600Y43457I-437J244D01*
G01X155685D01*
X154300Y44842D01*
Y49373D01*
X153014Y50659D01*
X151526D01*
G02X150527Y51683I1J1000D01*
G03X147523I-1502J37D01*
G02X146524Y50659I-1000J-24D01*
G01X146343D01*
G02X145347Y51752I0J1000D01*
G03X142367I-1490J191D01*
G02X141371Y50659I-996J-93D01*
G01X134535D01*
X90210Y6334D01*
X24220D01*
X18170Y12384D01*
Y97711D01*
X43643Y123184D01*
G02X45330Y122677I707J-707D01*
G03X47062Y124409I1481J251D01*
G02X46555Y126096I200J980D01*
G01X60857Y140398D01*
G02X61564I353J-354D01*
G01X61848Y140114D01*
X62081Y139880D01*
X64309D01*
G03X65528Y143470I0J2002D01*
G02X65429Y144970I608J793D01*
G01X73387Y152928D01*
X73477Y152966D01*
G03X74223Y153656I-587J1383D01*
G02X74667Y153926I444J-230D01*
G01X76030D01*
G03X77868Y154896I0J2226D01*
G02X78281Y155114I413J-282D01*
G01X81870D01*
X96720Y169964D01*
Y221245D01*
X96973Y221529D01*
X97163Y221551D01*
G03X98305Y223769I-173J1492D01*
G02Y224253I437J242D01*
G03X97163Y226471I-1315J726D01*
G01X97162D01*
G02X96720Y226968I58J497D01*
G01Y227651D01*
X97670Y228601D01*
Y231618D01*
G03X97653Y231841I-1502J-2D01*
G03X97632Y231953I-1485J-221D01*
G02X98639Y233149I980J196D01*
G03X99351Y233296I61J1501D01*
G03X99333Y236012I-651J1354D01*
G03X98101Y236027I-633J-1362D01*
G02X96720Y236952I-381J925D01*
G01Y239648D01*
G02X98241Y240501I1000J-1D01*
G03X109894Y249635I4121J6743D01*
G03X104392Y254881I-7532J-2391D01*
G01X104227Y254925D01*
X104020Y255194D01*
Y259632D01*
G02X104520Y260132I500J0D01*
G01X104550D01*
G03X106689Y262977I0J2227D01*
G03X106197Y263857I-2139J-618D01*
G02X106146Y264463I370J336D01*
G03X104270Y267888I-1876J1199D01*
G01X102932D01*
X100776Y270044D01*
Y305941D01*
X99957Y306761D01*
X99679Y307039D01*
Y311005D01*
X89920Y320764D01*
Y371618D01*
X82610Y378928D01*
Y387619D01*
X83094Y388109D01*
X83267Y388130D01*
G03Y391112I-183J1491D01*
G01X83094Y391133D01*
X82610Y391623D01*
Y395438D01*
G02X83464Y396427I1000J0D01*
G03Y399399I-219J1486D01*
G02X82610Y400388I146J989D01*
G01Y441225D01*
X83667Y442282D01*
G02X85031Y442329I707J-707D01*
G03X87239Y444350I1019J1103D01*
G02Y445514I813J582D01*
G03X87494Y446020I-1190J917D01*
G01X87530Y446145D01*
X94727Y453342D01*
X115504D01*
G02X116496Y452214I0J-1000D01*
G03X119464I1484J-233D01*
G02X120456Y453342I992J128D01*
G01X171603D01*
X175133Y449812D01*
X179005D01*
X179920Y448897D01*
Y440025D01*
X180078Y439867D01*
X181388D01*
G03X181422Y439866I61J1500D01*
G01X186676D01*
G02X187620Y438647I-31J-999D01*
G03X189468Y436831I1457J-366D01*
G03X190254Y439215I-391J1450D01*
G01X190205Y439276D01*
X190088Y439587D01*
X190150Y439874D01*
X190255Y439979D01*
X193510Y443234D01*
X197137D01*
X197573Y442798D01*
X205279D01*
X205715Y443234D01*
X208553D01*
X212204Y446885D01*
X255818D01*
X257580Y445123D01*
Y431278D01*
X254832Y428530D01*
X254656Y428512D01*
X254627Y428508D01*
X245629D01*
X245278Y428656D01*
X245213Y428715D01*
G03X243179I-1017J-1105D01*
G01X243114Y428656D01*
X242763Y428508D01*
X230288D01*
G02X229943Y428646I0J500D01*
G03X227869I-1037J-1086D01*
G01X227724Y428508D01*
X194987D01*
G02X194004Y429325I0J1000D01*
G03X191050I-1477J-276D01*
G02X190067Y428508I-983J183D01*
G01X185097D01*
G02X184210Y429969I0J1000D01*
G03X181544I-1333J693D01*
G02X180657Y428508I-887J-461D01*
G01X180462D01*
G02X179571Y429961I0J1000D01*
G03X176893I-1339J681D01*
G02X176002Y428508I-891J-453D01*
G01X174525D01*
G02X174182Y428644I0J500D01*
G03X173801Y428906I-1031J-1092D01*
G03X172736Y428996I-651J-1354D01*
G02X171631Y429397I-277J961D01*
G03X169099Y429409I-1270J-802D01*
G03X168927Y429042I1261J-815D01*
G01X168882Y428897D01*
X168402Y428508D01*
X126175D01*
X125420Y429263D01*
X111567D01*
X106280Y423976D01*
Y421338D01*
X106203Y421154D01*
X106168Y421119D01*
Y413264D01*
X105679Y412774D01*
X105505Y412755D01*
G03Y409769I165J-1493D01*
G01X105679Y409750D01*
X106168Y409260D01*
Y405089D01*
X108956Y402302D01*
X114618D01*
X116610Y400310D01*
Y395836D01*
X116343Y395400D01*
X116229Y395336D01*
G03X116322Y392663I731J-1313D01*
G01X116454Y392601D01*
X116610Y392356D01*
Y391616D01*
X116464Y391376D01*
X116340Y391312D01*
G03Y388644I690J-1334D01*
G01X116464Y388580D01*
X116610Y388340D01*
Y337629D01*
X114840Y335859D01*
Y275322D01*
X119248Y270914D01*
Y166696D01*
X114066Y161514D01*
G02X112511Y161690I-707J707D01*
G03X110453Y159632I-1291J-767D01*
G02X110629Y158077I-531J-848D01*
G01X80453Y127901D01*
G02X80100Y127754I-354J353D01*
G01X77758D01*
X77640Y127823D01*
G03X75380Y126442I-760J-1295D01*
G03X76081Y125256I1500J86D01*
G02X76256Y123703I-533J-846D01*
G01X65683Y113130D01*
X65536Y112983D01*
X65123Y112982D01*
X64974Y113131D01*
X64972Y113133D01*
G03X64387Y113502I-1072J-1052D01*
G03X62452Y112479I-487J-1421D01*
G03X64276Y110627I1448J-398D01*
G02X65500Y109652I224J-975D01*
G01Y75324D01*
G02X64399Y74328I-1000J-1D01*
G03Y71354I-209J-1487D01*
G02X65500Y70358I101J-995D01*
G01Y59643D01*
X65495Y59607D01*
G03X65482Y59484I1486J-219D01*
G03X65481Y59471I1496J-122D01*
G02X64482Y59487I-499J30D01*
G03X62652Y57975I-1501J-47D01*
G02X63104Y56300I-255J-967D01*
G01X42648Y35844D01*
X42613Y35819D01*
G03X42254Y35460I868J-1227D01*
G01X42253Y35459D01*
X42228Y35424D01*
X40820Y34016D01*
Y22106D01*
X40791Y22024D01*
G03Y21012I1414J-506D01*
G01X40820Y20930D01*
Y19736D01*
X42600D01*
X46880Y15456D01*
X54724D01*
X54744Y15455D01*
G03X54976I116J1497D01*
G01X54996Y15456D01*
X55751D01*
X97270Y56975D01*
X102908D01*
X104649Y58716D01*
X108874D01*
X118104Y67946D01*
X160025D01*
X163670Y64301D01*
Y62689D01*
G02X163515Y62327I-500J0D01*
G03Y60151I1035J-1088D01*
G02X163670Y59789I-345J-362D01*
G01Y59671D01*
X164383D01*
X165568Y58486D01*
X169618D01*
X170574Y59442D01*
X221014D01*
X224310Y56146D01*
X251423D01*
G02X252254Y54590I0J-1000D01*
G03X254333Y54979I1236J-854D01*
G01X254238Y55043D01*
X253988Y55477D01*
X254025Y55721D01*
G02X254519Y56146I494J-75D01*
G01X255554D01*
X256031Y55770D01*
X256079Y55630D01*
G03X256275Y55248I1421J488D01*
G03X256516Y54982I1226J868D01*
G01X256591Y54916D01*
X256706Y54686D01*
G02X256718Y54270I-449J-221D01*
G03X256773Y52990I1385J-582D01*
G03X258109Y52186I1330J698D01*
G03X259088Y54823I-6J1502D01*
G01X259012Y54889D01*
X258897Y55119D01*
G02X258885Y55535I449J221D01*
G03X258921Y55631I-1388J575D01*
G01X258969Y55770D01*
X259446Y56146D01*
X271018D01*
X271042Y56122D01*
X273186Y58265D01*
X347316D01*
G02X347670Y58118I0J-500D01*
G01X347980Y57807D01*
X347990Y57616D01*
G03X348317Y56760I1500J82D01*
G03X348682Y56432I1173J938D01*
G01X348782Y56368D01*
X349040Y55936D01*
Y36429D01*
X347774Y35163D01*
X343590D01*
X342690Y36063D01*
Y49351D01*
X338805Y53236D01*
X297382D01*
G02X296927Y53529I0J500D01*
G37*
G36*
G01X11331Y311647D02*
X7246Y315732D01*
Y376095D01*
X10270Y379119D01*
X22141D01*
X43158Y358111D01*
X43272Y357836D01*
X54480Y346627D01*
Y314318D01*
X51809Y311647D01*
X11331D01*
G37*
G36*
G01X121364Y675921D02*
G03X119478Y674035I-455J-1431D01*
G01X119520Y673901D01*
X119454Y673629D01*
X113484Y667659D01*
X87150D01*
X75070Y655579D01*
Y618497D01*
X66140Y609567D01*
Y591270D01*
X60531Y585661D01*
G02X58871Y586064I-707J707D01*
G03X56983Y584176I-1431J-457D01*
G02X57386Y582516I-304J-953D01*
G01X50622Y575752D01*
G02X50107Y575633I-353J354D01*
G03X48199Y573725I-487J-1421D01*
G02X48080Y573210I-473J-162D01*
G01X45112Y570242D01*
X40760D01*
X40758Y570240D01*
X30762D01*
X21700Y561178D01*
Y558284D01*
G02X20577Y557292I-1000J0D01*
G03Y554322I-227J-1485D01*
G02X21700Y553330I123J-992D01*
G01Y552464D01*
G02X20217Y551589I-1000J0D01*
G03X18004Y549891I-767J-1292D01*
G03X20707Y549474I1446J406D01*
G01X20771Y549572D01*
X20946Y549675D01*
G02X21700Y549244I254J-431D01*
G01Y548745D01*
G02X20680Y547745I-1000J0D01*
G03X19322Y546945I-30J-1502D01*
G03X21063Y544799I1328J-702D01*
G01X21130Y544818D01*
X21200D01*
G02X21700Y544318I0J-500D01*
G01Y544036D01*
X21698Y544034D01*
Y542455D01*
X20468Y541225D01*
X18974Y539730D01*
Y384627D01*
G02X18474Y384149I-500J23D01*
G01X7350D01*
G02X6850Y384649I0J500D01*
G01Y629433D01*
G02X8414Y630259I1000J0D01*
G03Y632685I886J1213D01*
G02X6850Y633511I-564J826D01*
G01Y636619D01*
G02X8394Y637458I1000J0D01*
G03Y639940I846J1241D01*
G02X6850Y640779I-544J839D01*
G01Y658610D01*
X10870Y662630D01*
X42460D01*
X58520Y678690D01*
Y786198D01*
X59772Y787450D01*
X70075D01*
X70189Y787386D01*
G03X71661I736J1309D01*
G01X71775Y787450D01*
X72920D01*
G02X73420Y786950I0J-500D01*
G01Y786945D01*
X85060Y775305D01*
X175328D01*
X184096Y766537D01*
Y749612D01*
X184057Y749519D01*
G03Y748353I1383J-583D01*
G01X184096Y748260D01*
Y736359D01*
X184057Y736266D01*
G03Y735096I1383J-585D01*
G01X184096Y735003D01*
Y732987D01*
G02X182953Y731997I-1000J0D01*
G03Y729045I-279J-1476D01*
G02X184096Y728055I143J-990D01*
G01Y724355D01*
G02X183596Y723855I-500J0D01*
G01X183578D01*
G03Y720851I-12J-1502D01*
G01X183596D01*
G02X184096Y720351I0J-500D01*
G01Y713177D01*
X184057Y713084D01*
G03Y711914I1383J-585D01*
G01X184096Y711821D01*
Y694524D01*
X182218Y692646D01*
X173529D01*
G02X173029Y693146I0J500D01*
G01Y711291D01*
X171583Y712737D01*
G02X171815Y714324I707J707D01*
G03X171187Y717175I-661J1349D01*
G01X170987Y717179D01*
X164624Y723542D01*
X140277D01*
X140267Y723552D01*
X128960D01*
X127675Y722267D01*
G02X127046Y722203I-354J354D01*
G03X124816Y721482I-826J-1254D01*
G03X124982Y720098I1404J-534D01*
G01X125070Y719970D01*
Y679245D01*
X121869Y676044D01*
G02X121364Y675921I-354J354D01*
G37*
G36*
G01X180922Y441368D02*
Y449312D01*
X179420Y450814D01*
X175548D01*
X172018Y454344D01*
X171010D01*
X170940Y454414D01*
X120499D01*
G02X119508Y455280I0J1000D01*
G03X116532I-1488J-201D01*
G02X115541Y454414I-991J134D01*
G01X47304D01*
X44730Y456988D01*
Y474954D01*
X45865Y476089D01*
X62856D01*
X66382Y472563D01*
X109484D01*
X111088Y470960D01*
X114369D01*
X116291Y469038D01*
X124135D01*
G02X125362Y469063I630J-777D01*
G03X125596Y468920I897J1205D01*
G02X125625Y468038I-221J-449D01*
G03X127406Y467833I753J-1300D01*
G02X127359Y469243I685J729D01*
G03X127762Y470257I-1099J1024D01*
G02X128762Y471250I1000J-7D01*
G01X132520D01*
X134061Y469709D01*
X134103Y469368D01*
X134014Y469219D01*
G03X135912Y467073I1286J-775D01*
G01X136010Y467116D01*
X169562D01*
X169703Y467257D01*
X170116D01*
X170305Y467069D01*
X170336Y467018D01*
G03X171238Y466350I1280J786D01*
G01X171369Y466316D01*
X174960Y462726D01*
X180227D01*
X187660Y455292D01*
Y441368D01*
G02X187160Y440868I-500J0D01*
G01X181422D01*
G02X180922Y441368I0J500D01*
G37*
G36*
G01X135129Y598584D02*
G02X134250Y597106I-879J-478D01*
G01X130956D01*
X130932Y597108D01*
G03X130648I-142J-1495D01*
G01X130624Y597106D01*
X97104D01*
X86590Y607620D01*
Y655964D01*
X90970Y660344D01*
X124809D01*
X129643Y655510D01*
X146820D01*
X156741Y645590D01*
G02X156805Y644246I-707J-707D01*
G03X157660Y641818I1158J-957D01*
G03X159406Y643704I303J1471D01*
G02X160377Y644946I971J242D01*
G01X160936D01*
G02X161436Y644446I0J-500D01*
G01Y644278D01*
X161334Y644144D01*
G03X162186Y641773I1196J-909D01*
G03X163969Y643667I344J1462D01*
G02X164929Y644946I960J279D01*
G01X201194D01*
X202950Y643190D01*
Y640442D01*
X202759Y640179D01*
X202604Y640129D01*
G03Y637271I461J-1429D01*
G01X202759Y637221D01*
X202950Y636958D01*
Y626006D01*
G02X202465Y625506I-500J0D01*
G03Y622504I45J-1501D01*
G02X202950Y622004I-15J-500D01*
G01Y610199D01*
X202843Y610063D01*
G03Y608207I1181J-928D01*
G01X202950Y608071D01*
Y605199D01*
X202843Y605063D01*
G03Y603207I1181J-928D01*
G01X202950Y603071D01*
Y598948D01*
X201108Y597106D01*
X147212D01*
G02X146212Y598118I0J1000D01*
G03X145237Y599542I-1502J17D01*
G03X143513Y599042I-527J-1407D01*
G02X142112Y598871I-786J618D01*
G03X139709Y597938I-922J-1186D01*
G02X138724Y597106I-986J168D01*
G01X138590D01*
G02X137711Y598584I0J1000D01*
G03X135129I-1291J768D01*
G37*
G36*
G01X174265Y426544D02*
G03X174527Y426950I-1115J1007D01*
G02X174985Y427249I458J-201D01*
G01X225988D01*
X226240Y426997D01*
X227210D01*
X227626Y426766D01*
X227690Y426678D01*
G03X227695Y426672I1155J958D01*
G03X227717Y426642I1222J873D01*
G02Y425478I-813J-582D01*
G03X230095I1189J-918D01*
G02Y426642I813J582D01*
G03X230140Y426704I-1193J913D01*
G03X230181Y426765I-1226J868D01*
G01X230250Y426874D01*
X230474Y426997D01*
X242671D01*
X242888Y426863D01*
X242949Y426773D01*
G03X243054Y426635I1246J839D01*
G02Y425985I-380J-325D01*
G03X245338I1142J-975D01*
G02Y426635I380J325D01*
G03X245444Y426775I-1142J975D01*
G01X245515Y426880D01*
X245734Y426997D01*
X252880D01*
G02X253363Y426627I0J-500D01*
G03X256296Y426782I1450J391D01*
G01X256576Y426997D01*
X280114D01*
X286030Y421081D01*
Y408993D01*
X280906Y403869D01*
X280772Y403835D01*
G03X279686Y402749I370J-1456D01*
G01X279652Y402615D01*
X277475Y400438D01*
X274720D01*
G02X273721Y401400I0J1000D01*
G03X270719I-1501J-57D01*
G02X269720Y400438I-999J38D01*
G01X267664D01*
G02X266664Y401419I0J1000D01*
G03X263660I-1502J-28D01*
G02X262660Y400438I-1000J19D01*
G01X225573D01*
G02X224579Y401544I0J1000D01*
G03X221591I-1494J158D01*
G02X220597Y400438I-994J-106D01*
G01X216544D01*
X216344Y400532D01*
X216272Y400617D01*
G03X215744Y401020I-1153J-963D01*
G02X215200Y402044I448J894D01*
G03X213450Y403716I-1490J193D01*
G03X212694Y403343I260J-1479D01*
G02X211987Y403374I-338J369D01*
G03X211675Y403633I-1107J-1016D01*
G03X209483Y401806I-795J-1274D01*
G02X208554Y400438I-930J-368D01*
G01X207933D01*
G02X207433Y400938I0J500D01*
G01Y401116D01*
X207545Y401253D01*
G03X207633Y401373I-1166J947D01*
G03X206611Y403685I-1253J828D01*
G03X204957Y401721I-231J-1484D01*
G02X203997Y400438I-959J-283D01*
G01X185711D01*
X176270Y409879D01*
X134860D01*
X134054Y409074D01*
X133525D01*
X129958Y405507D01*
Y404978D01*
X125943Y400962D01*
G02X125590Y400816I-353J354D01*
G01X117520D01*
X115033Y403304D01*
X109371D01*
X108730Y403944D01*
X107170Y405504D01*
Y411195D01*
G03Y411329I-1500J67D01*
G01Y420704D01*
X113715Y427249D01*
X126614D01*
G02X127584Y426008I-1J-1000D01*
G03X130472I1444J-415D01*
G02X131442Y427249I971J241D01*
G01X137178D01*
G02X138065Y425789I-1J-1000D01*
G03X138032Y425722I1331J-697D01*
G03X139609Y423603I1363J-632D01*
G02X140748Y422527I143J-990D01*
G03X143326Y421309I1491J-181D01*
G03X142025Y423833I-1086J1037D01*
G02X140886Y424909I-143J990D01*
G03X140725Y425789I-1491J182D01*
G02X141612Y427249I888J460D01*
G01X169687D01*
X169780Y427210D01*
G03X170942I581J1385D01*
G01X171035Y427249D01*
X171317D01*
G02X171775Y426950I0J-500D01*
G03X172446Y426226I1376J602D01*
G01X172552Y426170D01*
X172693Y425968D01*
G02X172572Y425271I-409J-288D01*
G01X172556Y425260D01*
X172538Y425250D01*
G02X171430Y425311I-508J861D01*
G03X169659Y425367I-924J-1184D01*
G03X169080Y424599I847J-1240D01*
G03X171330Y422871I1426J-472D01*
G02X172457Y422821I527J-850D01*
G03X174362Y425143I924J1184D01*
G02X174265Y426544I662J750D01*
G37*
G36*
G01X258254Y261562D02*
G02X258815Y261359I144J-479D01*
G03X261320Y261357I1253J828D01*
G01X261385Y261455D01*
X261590Y261573D01*
X261827Y261587D01*
X262043Y261493D01*
X262120Y261402D01*
G03X262233Y261282I1148J968D01*
G01X262301Y261217D01*
X262368Y261073D01*
G02X262351Y260619I-454J-210D01*
G01X262242Y260423D01*
X262152Y260358D01*
G03X262176Y257902I877J-1220D01*
G01X262270Y257837D01*
X262410Y257593D01*
G02X262425Y257125I-434J-248D01*
G03X264958Y255540I1349J-661D01*
G02X266256Y255786I789J-615D01*
G03X265836Y258003I764J1293D01*
G02X264537Y257757I-789J615D01*
G01X264291Y258189D01*
X264351Y258426D01*
G03X264242Y260024I-1322J713D01*
G02X264338Y261316I808J590D01*
G03X264320Y263443I-1070J1055D01*
G01X264253Y263508D01*
X264085Y263879D01*
X264194Y264188D01*
X264238Y264248D01*
G03X264494Y264808I-1209J891D01*
G01X264534Y264984D01*
X264678Y265095D01*
G02X265005Y265197I303J-398D01*
G03X264982Y268196I68J1500D01*
G02X264472Y268556I-30J499D01*
G03X264024Y269264I-1443J-417D01*
G02Y270014I331J375D01*
G03X264140Y270128I-993J1127D01*
G01X264206Y270200D01*
X264588Y270383D01*
X265189D01*
X265285Y270341D01*
G03X266487I601J1377D01*
G01X266583Y270383D01*
X268554D01*
G02X269026Y270049I0J-500D01*
G01Y270048D01*
G03X271344Y269341I1418J495D01*
G02X272544I600J-800D01*
G03X274344I900J1202D01*
G02X275544I600J-800D01*
G03X277344I900J1202D01*
G02X278544I600J-800D01*
G03X279170Y269066I901J1202D01*
G01X279323Y269038D01*
X280352Y268009D01*
X290252D01*
G02X291234Y266822I0J-1000D01*
G03X293730Y265439I1476J-280D01*
G02X294987Y265521I679J-734D01*
G03X295181Y265393I922J1186D01*
G02X294981Y264457I-242J-438D01*
G03X294573Y261558I129J-1496D01*
G03X296296Y263883I538J1402D01*
G02X296601Y265372I789J614D01*
G03X297396Y266490I-691J1333D01*
G03X297401Y266888I-1486J218D01*
G02X298394Y268009I993J121D01*
G01X326812D01*
X339704Y255117D01*
Y153860D01*
X339419Y153569D01*
X339214Y153565D01*
G03Y150561I31J-1502D01*
G01X339419Y150557D01*
X339704Y150266D01*
Y111311D01*
X330469Y102076D01*
G02X329038Y102093I-707J707D01*
G03X328909Y102213I-1086J-1038D01*
G02X328606Y103316I639J769D01*
G03X326231Y102662I-1416J502D01*
G02X326534Y101559I-639J-769D01*
G03X326453Y101182I1416J-501D01*
G02X325662Y100287I-996J84D01*
G03X324857Y97809I308J-1470D01*
G02X324823Y96430I-741J-672D01*
G01X324235Y95842D01*
X319935D01*
X319454Y96239D01*
X319411Y96385D01*
G03X319315Y96629I-1440J-426D01*
G02X319418Y97214I448J223D01*
G02X320007Y97288I345J-362D01*
G03X319241Y98508I733J1311D01*
G02X318134Y97454I-998J-60D01*
G03X316529Y96386I-164J-1493D01*
G01X316486Y96239D01*
X316005Y95842D01*
X314687D01*
G02X313702Y96668I0J1000D01*
G03X312800Y97794I-1479J-261D01*
G02X312251Y99078I384J923D01*
G03X310273Y98233I-1401J542D01*
G02X310822Y96949I-384J-923D01*
G03X310744Y96668I1401J-540D01*
G02X309759Y95842I-985J174D01*
G01X304025D01*
G02X303611Y96060I-1J500D01*
G03X303514Y96188I-1244J-842D01*
G02X303726Y96983I381J324D01*
G03X301872Y97734I-506J1414D01*
G02X301533Y96462I-897J-442D01*
G03X301129Y96061I837J-1247D01*
G02X300715Y95842I-414J281D01*
G01X297965D01*
G02X296976Y96989I0J1000D01*
G03X296348Y98442I-1486J220D01*
G02X296072Y99794I571J821D01*
G03X296301Y100547I-1272J798D01*
G02X297151Y101506I1000J-30D01*
G03X295426Y103037I-224J1485D01*
G02X294576Y102078I-1000J30D01*
G03X294064Y101903I222J-1486D01*
G02X293347Y102502I-245J436D01*
G03X292150Y101506I-1420J489D01*
G02X293299Y100547I149J-989D01*
G03X293942Y99360I1501J46D01*
G02X294218Y98008I-571J-821D01*
G03X293993Y97333I1272J-799D01*
G02X293200Y96436I-996J82D01*
G03X292415Y95998I306J-1471D01*
G01X292344Y95923D01*
X292155Y95842D01*
X291517D01*
X291234Y96092D01*
X291210Y96280D01*
Y96281D01*
G03X288668Y97166I-1490J-187D01*
G02X287465Y97015I-701J714D01*
G03X285329Y96307I-755J-1298D01*
G01X285274Y96180D01*
X284808Y95842D01*
X276343D01*
G02X275396Y97163I0J1000D01*
G03X272550I-1423J482D01*
G02X271603Y95842I-947J-321D01*
G01X266711D01*
G02X265711Y96871I0J1000D01*
G03X265228Y98018I-1501J43D01*
G02X265017Y99213I678J736D01*
G03X265181Y100014I-1334J690D01*
G02X266039Y101079I997J75D01*
G03X264332Y102454I-209J1487D01*
G02X263474Y101389I-997J-75D01*
G03X262665Y98798I209J-1487D01*
G02X262876Y97603I-678J-736D01*
G03X262709Y96871I1334J-689D01*
G02X261709Y95842I-1000J-29D01*
G01X255077D01*
X254704Y96013D01*
X254639Y96081D01*
G03X252418Y96016I-1081J-1043D01*
G02X252039Y95842I-379J326D01*
G01X249967D01*
X249769Y95933D01*
X249698Y96016D01*
G03X247477Y96081I-1140J-978D01*
G01X247412Y96013D01*
X247039Y95842D01*
X237792D01*
G02X236792Y96858I0J1000D01*
G03X236010Y98256I-1595J25D01*
G02X235609Y99532I509J861D01*
G03X233426Y98896I-1366J624D01*
G02X233774Y97604I-544J-839D01*
G03X233620Y97126I1423J-722D01*
G02X232812Y96294I-989J152D01*
G03X232110Y95961I271J-1477D01*
G01X231970Y95842D01*
X216406D01*
G02X215408Y96895I1J1000D01*
G03X212408I-1500J80D01*
G02X211410Y95842I-999J-53D01*
G01X211406D01*
G02X210408Y96895I1J1000D01*
G03X208727Y98466I-1500J80D01*
G02X207698Y99039I-121J993D01*
G03X207367Y99509I-1448J-669D01*
G02X207203Y100724I701J713D01*
G03X204802Y100456I-1300J753D01*
G02X204909Y99234I-734J-680D01*
G03X204960Y97431I1341J-864D01*
G02X204152Y95842I-808J-589D01*
G01X202835D01*
G02X201894Y97180I0J1000D01*
G03X199066I-1414J507D01*
G02X198125Y95842I-941J-338D01*
G01X197846D01*
G02X197385Y96148I0J500D01*
G01Y96149D01*
G03X194615I-1385J-581D01*
G01Y96148D01*
G02X194154Y95842I-461J194D01*
G01X185823D01*
G02X185410Y96060I0J500D01*
G03X184759Y96595I-1241J-846D01*
G02X184297Y98033I393J919D01*
G03X184367Y98163I-1286J776D01*
G02X185585Y98678I901J-433D01*
G03X184706Y100753I475J1425D01*
G02X183488Y100238I-901J433D01*
G03X182816Y97324I-475J-1425D01*
G01X182987Y97301D01*
X183212Y97070D01*
G02X183203Y96363I-358J-349D01*
G01X183193Y96354D01*
X183183Y96344D01*
G03X182930Y96060I986J-1133D01*
G01X182860Y95958D01*
X182641Y95842D01*
X179576D01*
G02X178630Y97168I-1J1000D01*
G03X176218Y98785I-1420J489D01*
G02X174895Y98787I-660J751D01*
G03X172481Y97170I-995J-1125D01*
G02X171536Y95842I-945J-328D01*
G01X157546D01*
G02X156593Y97146I0J1000D01*
G03X147345I-4624J1476D01*
G02X146393Y95842I-953J-304D01*
G01X142486D01*
X130929Y98934D01*
X129438Y100425D01*
Y100465D01*
X125950Y103953D01*
Y140719D01*
X129438Y144207D01*
Y219022D01*
X139751Y229335D01*
X175411D01*
X175698Y229068D01*
X175712Y228871D01*
G03X177625Y227535I1498J107D01*
G03X179538Y228871I415J1443D01*
G01X179552Y229068D01*
X179839Y229335D01*
X182641D01*
X182839Y229244D01*
X182910Y229161D01*
G03X185190I1140J978D01*
G01X185261Y229244D01*
X185459Y229335D01*
X203057D01*
G02X204044Y228498I0J-1000D01*
G03X204270Y227873I1490J186D01*
G03X207037Y228685I1265J808D01*
G03X206907Y229291I-1502J-5D01*
G01X206844Y229434D01*
X206901Y229739D01*
X210498Y233336D01*
X210890Y233350D01*
X211039Y233222D01*
G03X211488Y232955I980J1138D01*
G02X211466Y232012I-177J-468D01*
G03X212946Y231696I469J-1427D01*
G02X212971Y233196I674J739D01*
G03X213157Y235340I-951J1163D01*
G01X213029Y235489D01*
X213043Y235881D01*
X214172Y237010D01*
G02X215777Y236743I707J-707D01*
G03X218584Y236988I1358J642D01*
G03X218237Y238406I-1449J397D01*
G02Y239764I734J679D01*
G03X218556Y241272I-1102J1021D01*
G01X218529Y241351D01*
Y243519D01*
X218556Y243598D01*
G03Y244572I-1421J487D01*
G01X218529Y244651D01*
Y250169D01*
G02X219626Y251164I1000J0D01*
G03X220753Y251522I145J1495D01*
G03X220171Y254107I-981J1137D01*
G03X219215Y254054I-399J-1448D01*
G01X219125Y254018D01*
X219029D01*
G02X218529Y254518I0J500D01*
G01Y254901D01*
X218735Y255169D01*
X218899Y255214D01*
X218900D01*
G03Y258114I-392J1450D01*
G01X218899D01*
X218735Y258159D01*
X218529Y258427D01*
Y258897D01*
G02X218810Y259346I500J0D01*
G03X219539Y260117I-657J1351D01*
G03X219342Y261615I-1386J580D01*
G02Y262779I813J582D01*
G03X219291Y264677I-1189J918D01*
G01X219163Y264826D01*
X219177Y265218D01*
X221968Y268009D01*
X237095D01*
G02X238087Y266885I0J-1000D01*
G03X238380Y265721I1482J-246D01*
G02Y264557I-813J-582D01*
G03Y262721I1189J-918D01*
G02Y261557I-813J-582D01*
G03Y259721I1189J-918D01*
G02Y258557I-813J-582D01*
G03X238068Y257597I1189J-917D01*
G03X240571Y256520I1501J41D01*
G03X241034Y257308I-1002J1119D01*
G01X241074Y257485D01*
X241218Y257595D01*
G02X241545Y257697I303J-398D01*
G03X242802Y260115I68J1500D01*
G02Y261279I813J582D01*
G03X241522Y263696I-1189J918D01*
G02X241012Y264057I-30J499D01*
G03X240996Y264108I-1441J-424D01*
G03X240758Y264557I-1427J-469D01*
G02Y265721I813J582D01*
G03X241034Y266308I-1189J918D01*
G01X241074Y266484D01*
X241218Y266595D01*
G02X241545Y266697I303J-398D01*
G03X242509Y266992I68J1500D01*
G03X243024Y267681I-895J1206D01*
G02X243493Y268009I469J-172D01*
G01X245650D01*
X245912Y267820D01*
X245963Y267666D01*
G03X248815I1426J473D01*
G02X249290Y268009I475J-157D01*
G01X252898D01*
G02X253886Y266848I1J-1000D01*
G03X256836Y266286I1473J-291D01*
G02X257310Y266696I492J-90D01*
G03X258664Y267681I-57J1501D01*
G02X259133Y268009I469J-172D01*
G01X259568D01*
X259876Y268317D01*
G02X261561Y267822I708J-707D01*
G03X261827Y267239I1468J318D01*
G02Y266039I-800J-600D01*
G03X261977Y264066I1202J-901D01*
G01X262044Y264001D01*
X262212Y263630D01*
X262103Y263321D01*
X262059Y263261D01*
G03X262016Y263200I1206J-896D01*
G02X261217Y263154I-417J276D01*
G03X259276Y263463I-1149J-967D01*
G02X258016Y263632I-527J850D01*
G03X255422Y262764I-1100J-1023D01*
G01X255406Y262607D01*
X254996Y262135D01*
X254843Y262096D01*
G03X255463Y259159I366J-1457D01*
G01X255761Y258948D01*
X255810Y258780D01*
G03X255845Y258675I1441J422D01*
G02X255670Y258096I-469J-174D01*
G03X257961Y257404I883J-1215D01*
G02X258136Y257982I469J174D01*
G03X258241Y260329I-883J1215D01*
G02X257898Y261083I657J754D01*
G02X258254Y261562I500J0D01*
G37*
G36*
G01X131539Y271213D02*
G03X131176Y273333I-1215J883D01*
G02X130960Y273745I284J412D01*
G01Y274789D01*
X130819Y274931D01*
G02X130821Y275638I355J352D01*
G01X130883Y275699D01*
X130961Y275736D01*
G03X131321Y278219I-637J1360D01*
G02X131056Y279336I664J748D01*
G03X129945Y281365I-1396J554D01*
G02X129540Y281856I95J491D01*
G01Y282010D01*
G02X129770Y282431I500J0D01*
G03X130215Y284521I-810J1265D01*
G02X130475Y285887I836J549D01*
G03X128738Y288338I-865J1228D01*
G02X127450Y288445I-581J814D01*
G01X125230Y290665D01*
Y320262D01*
X130960Y325992D01*
Y405092D01*
X133940Y408072D01*
X160599D01*
G02X161535Y406719I0J-1000D01*
G03X161491Y405791I1405J-532D01*
G02X160972Y404631I-964J-265D01*
G03X163089Y403683I668J-1345D01*
G02X163608Y404843I964J265D01*
G03X164345Y406719I-668J1345D01*
G02X165281Y408072I936J353D01*
G01X169693D01*
X171248Y406517D01*
X171270Y406348D01*
G03X171708Y405468I1490J192D01*
G02X171712Y404757I-350J-357D01*
G01X169470Y402515D01*
Y383512D01*
X174250Y378732D01*
Y338205D01*
G02X174031Y337791I-500J0D01*
G03X173951Y335365I845J-1242D01*
G01X174035Y335300D01*
X174250Y334894D01*
Y319800D01*
X171920Y317470D01*
Y308150D01*
G02X171420Y307650I-500J0D01*
G01X170843D01*
X169969Y308524D01*
X164047D01*
G02X163104Y309856I0J1000D01*
G03X160270I-1417J499D01*
G02X159327Y308524I-943J-332D01*
G01X157654D01*
X155996Y310182D01*
G03X153166Y307352I-1415J-1415D01*
G01X155996Y304522D01*
X159719D01*
G02X160703Y303343I0J-1000D01*
G03X163659I1478J-268D01*
G02X164643Y304522I984J179D01*
G01X168311D01*
X169185Y303648D01*
X171420D01*
G02X171920Y303148I0J-500D01*
G01Y288408D01*
X178166Y282162D01*
G02X177685Y280481I-707J-707D01*
G03X176876Y279985I340J-1463D01*
G02X176200Y279903I-382J322D01*
G03X176467Y277720I-882J-1216D01*
G02X177143Y277802I382J-322D01*
G03X179488Y278678I882J1216D01*
G02X181169Y279159I974J-226D01*
G01X181580Y278748D01*
G02X181724Y278350I-354J-353D01*
G01X181720Y278304D01*
X181717Y278285D01*
G03X181871Y277331I1481J-250D01*
G02X181324Y275921I-884J-468D01*
G03X180926Y275705I492J-1382D01*
G02X179710I-608J794D01*
G03X177665Y275447I-892J-1165D01*
G02X176175Y275354I-786J618D01*
G03X173684Y273840I-1057J-1067D01*
G02X173268Y272700I-955J-298D01*
G03X173109Y272582I814J-1262D01*
G02X171810Y272589I-645J764D01*
G03X171798Y270305I-981J-1137D01*
G02X173097Y270298I645J-764D01*
G03X175512Y271882I981J1137D01*
G02X175928Y273022I955J298D01*
G03X176310Y273374I-811J1264D01*
G02X177799Y273485I794J-608D01*
G03X179710Y273375I1019J1055D01*
G02X180926I608J-794D01*
G03X182837Y275596I892J1165D01*
G01X182769Y275662D01*
X182694Y275824D01*
G02X182940Y276487I455J208D01*
G01X183045Y276535D01*
X183161Y276532D01*
G03X183467Y276556I36J1502D01*
G01X183468D01*
G02X183910Y276418I89J-492D01*
G01X184218Y276110D01*
X184778D01*
Y276020D01*
X199211D01*
G02X200197Y274848I1J-1000D01*
G03X203137I1470J-306D01*
G02X204123Y276020I985J172D01*
G01X213360D01*
X214499Y274881D01*
G02X214636Y274431I-354J-354D01*
G03X214803Y273397I1473J-293D01*
G03X214834Y273345I1305J743D01*
G01X214910Y273223D01*
Y272055D01*
X214834Y271933D01*
G03Y270345I1275J-794D01*
G01X214910Y270223D01*
Y269323D01*
X214861Y269221D01*
G03Y267953I1323J-634D01*
G01X214910Y267851D01*
Y266055D01*
X214834Y265933D01*
G03Y264345I1275J-794D01*
G01X214910Y264223D01*
Y263055D01*
X214834Y262933D01*
G03Y261345I1275J-794D01*
G01X214910Y261223D01*
Y254310D01*
G02X214747Y253941I-500J0D01*
G03Y251725I1014J-1108D01*
G02X214910Y251356I-337J-369D01*
G01Y250206D01*
X210110Y245406D01*
X199408D01*
X199309Y245451D01*
G03X198061I-624J-1366D01*
G01X197962Y245406D01*
X186510D01*
G02X185634Y246888I0J1000D01*
G03X183002I-1316J724D01*
G02X182126Y245406I-876J-482D01*
G01X164016D01*
X163946Y245427D01*
G03X163090I-428J-1440D01*
G01X163020Y245406D01*
X146619D01*
G02X145732Y246868I0J1000D01*
G03X145804Y247028I-1331J695D01*
G02X147071Y247616I935J-355D01*
G03X146166Y249566I499J1417D01*
G02X144899Y248978I-935J355D01*
G03X143212Y248480I-499J-1417D01*
G02X141714Y248385I-791J612D01*
G01X130960Y259139D01*
Y267658D01*
X131073Y267875D01*
X131173Y267945D01*
G03X131534Y270045I-863J1229D01*
G02X131539Y271213I814J581D01*
G37*
G36*
G01X351020Y533748D02*
G02X350667Y533270I-500J0D01*
G03Y530400I443J-1435D01*
G01X350824Y530351D01*
X351020Y530087D01*
Y524754D01*
X347324Y521057D01*
Y520300D01*
X345630Y518606D01*
X345577Y518574D01*
G03X345062Y518059I773J-1288D01*
G01X345030Y518006D01*
X344660Y517636D01*
Y512988D01*
X344294Y512621D01*
Y500465D01*
G02X343344Y499466I-1000J0D01*
G03Y496466I76J-1500D01*
G02X344294Y495467I-50J-999D01*
G01Y486693D01*
X341727Y484126D01*
G02X340415Y484037I-707J707D01*
G03X338180Y482135I-909J-1196D01*
G02X337883Y480854I-883J-470D01*
G03X337271Y479820I879J-1218D01*
G01X337250Y479649D01*
X334560Y476960D01*
X334010D01*
X326409Y469359D01*
X307858D01*
G03X307742I-58J-1500D01*
G01X302959D01*
G02X302459Y469859I0J500D01*
G01Y469997D01*
X302530Y470115D01*
G03X302667Y470417I-1291J768D01*
G02X303623Y471105I950J-312D01*
G03X304833Y473507I8J1502D01*
G02Y474707I800J600D01*
G03X305016Y475026I-1201J901D01*
G02X306051Y475633I922J-387D01*
G03X306296Y475625I171J1492D01*
G01X306418Y475630D01*
X306529Y475579D01*
G02X306773Y474916I-210J-454D01*
G01X306699Y474754D01*
X306631Y474689D01*
G03X308822Y472641I1039J-1085D01*
G01X308949Y472792D01*
X309144Y472817D01*
G02X309499Y472726I62J-496D01*
G03X309228Y474906I881J1216D01*
G02X308550Y474821I-384J320D01*
G03X308136Y475033I-883J-1214D01*
G02X307557Y476440I311J950D01*
G03X304835Y477706I-1337J684D01*
G02X303800Y477099I-922J387D01*
G03X302429Y474707I-169J-1492D01*
G02Y473507I-800J-600D01*
G03X302204Y473075I1202J-901D01*
G02X301248Y472387I-950J312D01*
G03X299772Y470569I-8J-1502D01*
G02X298794Y469359I-978J-210D01*
G01X290052D01*
G02X289059Y470475I0J1000D01*
G03X287122Y472084I-1492J174D01*
G02X285829Y472957I-297J955D01*
G03X284777Y471399I-1497J-123D01*
G02X286070Y470526I297J-955D01*
G03X286075Y470475I1497J121D01*
G02X285082Y469359I-993J-116D01*
G01X284129D01*
X283027Y470460D01*
X279064D01*
X277973Y469370D01*
X277247D01*
G02X276870Y470198I0J500D01*
G01X277007Y470355D01*
X277162Y470393D01*
G03X275749Y472917I-353J1460D01*
G02X274430Y472836I-706J709D01*
G03X272218Y470881I-921J-1187D01*
G02X271359Y469370I-859J-511D01*
G01X225303D01*
X221260Y473413D01*
X220041D01*
G02X219541Y473898I0J500D01*
G03X216705Y474542I-1501J-45D01*
G03X216541Y473951I1335J-689D01*
G01X216528Y473752D01*
X216241Y473483D01*
X182522D01*
X180802Y475203D01*
G02X180848Y476662I707J708D01*
G03X178729Y478781I-991J1128D01*
G02X177270Y478735I-751J661D01*
G01X172540Y483465D01*
X142577D01*
X134698Y491344D01*
G02X134736Y492794I707J707D01*
G03X132849Y495126I-1005J1116D01*
G02X131676I-587J810D01*
G03X130827Y495412I-882J-1216D01*
G01X130626Y495416D01*
X117520Y508522D01*
Y508812D01*
G02X118033Y509311I500J-1D01*
G01X118051D01*
G03X118362Y512294I72J1500D01*
G02X117520Y513281I158J987D01*
G01Y523099D01*
X141326Y546905D01*
G02X142867Y546749I707J-708D01*
G03X145151Y546484I1253J828D01*
G01X145215Y546545D01*
X145571Y546697D01*
X145902Y546569D01*
X145965Y546518D01*
G03X145889Y548770I955J1160D01*
G01X145825Y548709D01*
X145469Y548557D01*
X145138Y548685D01*
X145075Y548736D01*
G03X144948Y548830I-956J-1158D01*
G02X144792Y550371I552J834D01*
G01X154157Y559736D01*
X154443Y559798D01*
X154582Y559747D01*
X154583D01*
G03X156515Y561680I526J1406D01*
G02X156630Y562209I468J175D01*
G01X156857Y562436D01*
X167336D01*
G02X167825Y562041I0J-500D01*
G03X168343Y561195I1468J317D01*
G02X168432Y559728I-632J-775D01*
G03X170371Y559809I1012J-971D01*
G02X170337Y561278I661J750D01*
G03X170474Y561429I-1042J1083D01*
G02X171911Y561570I786J-618D01*
G03X174274Y562129I978J1140D01*
G02X174735Y562436I461J-193D01*
G01X175140D01*
X179886Y567182D01*
Y567216D01*
X180072Y567477D01*
X180225Y567529D01*
G03X180894Y567989I-485J1422D01*
G01X181044Y568169D01*
X181146D01*
X181580Y568603D01*
X183270D01*
X191079Y560794D01*
X221944D01*
X222341Y560593D01*
X222407Y560513D01*
G03X224715I1154J962D01*
G01X224781Y560593D01*
X225178Y560794D01*
X233199D01*
X241942Y552051D01*
X241956Y552035D01*
X241958Y552033D01*
G03X242211Y551798I1118J950D01*
G01X242238Y551779D01*
G03X242301Y551737I845J1199D01*
G01X242412Y551669D01*
X242538Y551443D01*
Y551312D01*
X244466Y549383D01*
Y519679D01*
X241472Y516685D01*
X239155D01*
G02X238191Y517950I0J1000D01*
G03X237905Y519276I-1415J389D01*
G02Y520552I770J638D01*
G03Y522426I-1129J937D01*
G02Y523702I770J638D01*
G03X237910Y523708I-1124J941D01*
G03X237949Y523758I-1137J927D01*
G01X238019Y523853D01*
X238230Y523960D01*
X238468Y523961D01*
X238679Y523856D01*
X238751Y523760D01*
G03X241032Y525602I1175J879D01*
G02Y526825I792J612D01*
G03X238962Y528895I-1107J963D01*
G02X237736Y528897I-612J792D01*
G03X237116Y529215I-960J-1109D01*
G03X236327Y529185I-341J-1427D01*
G03X235839Y528917I449J-1397D01*
G02X234563I-638J770D01*
G03X232689I-937J-1129D01*
G02X231413I-638J770D01*
G03X231036Y529144I-937J-1129D01*
G03X229367Y526828I-560J-1356D01*
G02Y525599I-790J-614D01*
G03X229049Y524979I1109J-960D01*
G03X229079Y524190I1427J-341D01*
G03X229347Y523702I1397J449D01*
G02Y522426I-770J-638D01*
G03Y520552I1129J-937D01*
G02Y519276I-770J-638D01*
G03X229061Y517950I1129J-937D01*
G02X228097Y516685I-964J-265D01*
G01X219430D01*
G02X218975Y516977I0J500D01*
G03X216731Y517572I-1366J-624D01*
G02X215551Y517631I-550J835D01*
G03X214868Y517939I-925J-1139D01*
G03X214480Y517952I-243J-1447D01*
G03X213745Y517665I146J-1460D01*
G02X212556Y517719I-558J830D01*
G03X212390Y517836I-946J-1166D01*
G03X212255Y517909I-781J-1283D01*
G03X210184Y517027I-646J-1356D01*
G02X209709Y516685I-474J158D01*
G01X209228D01*
X191208Y498665D01*
Y488933D01*
X194558Y485583D01*
X196119D01*
X197157Y484545D01*
X209717D01*
X210755Y485583D01*
X212618D01*
X214779Y487744D01*
X214966Y487756D01*
G02X215302Y487656I34J-499D01*
G03X217351Y487878I907J1197D01*
G02X217731Y488053I380J-325D01*
G01X218548D01*
X218652Y488003D01*
G03X219966I657J1350D01*
G01X220070Y488053D01*
X221448D01*
X221552Y488003D01*
G03X222866I657J1350D01*
G01X222970Y488053D01*
X263082D01*
X265427Y490398D01*
G02X266776Y490457I707J-707D01*
G03X269002Y490792I965J1151D01*
G02X269422Y491021I420J-271D01*
G01X286610D01*
X286638Y490993D01*
X298982D01*
G02X299872Y489537I0J-1000D01*
G03X302374Y487905I1337J-684D01*
G02X302998Y488030I388J-316D01*
G03X305161Y489737I711J1323D01*
G02X306128Y490993I967J256D01*
G01X306510D01*
X316993Y501476D01*
Y508051D01*
X320170Y511228D01*
X320328Y511255D01*
G03X321561Y512487I-248J1481D01*
G01Y512488D01*
X321588Y512646D01*
X325684Y516742D01*
G02X326069Y516887I353J-354D01*
G01X326071D01*
G03X327669Y518479I99J1499D01*
G01Y518485D01*
X327668Y518502D01*
G02X327815Y518873I500J17D01*
G01X331390Y522448D01*
Y541595D01*
G02X332397Y542595I1000J0D01*
G03Y545599I11J1502D01*
G02X331390Y546599I-7J1000D01*
G01Y556771D01*
X339566Y564947D01*
G02X341039Y564883I707J-707D01*
G03X343155Y566999I1151J965D01*
G02X343091Y568472I643J766D01*
G01X371238Y596619D01*
X390836D01*
X390944Y596564D01*
G03X392316I686J1336D01*
G01X392424Y596619D01*
X399784D01*
G02X400193Y596407I0J-500D01*
G01Y596406D01*
G03X401973Y595873I1229J864D01*
G02X403340Y594942I367J-930D01*
G01Y590366D01*
X404540Y589166D01*
X409320D01*
X412463Y592309D01*
G02X412868Y592453I354J-353D01*
G03X414464Y594368I154J1494D01*
G02X415424Y595648I960J280D01*
G01X421827D01*
X422798Y596619D01*
X427639D01*
X427891Y596450D01*
X427949Y596308D01*
G03X430731I1391J566D01*
G01X430788Y596449D01*
X431042Y596619D01*
X467942D01*
X468419Y596241D01*
X468466Y596101D01*
G03X469188Y595252I1424J479D01*
G02X469708Y594207I-467J-884D01*
G03X471622Y595402I1482J-243D01*
G02X471298Y596055I144J479D01*
G03X471314Y596101I-1411J517D01*
G01X471361Y596241D01*
X471838Y596619D01*
X476113D01*
X479912Y592820D01*
X479950Y592727D01*
G03X480771Y591906I1390J569D01*
G01X480864Y591868D01*
X484437Y588295D01*
X484486Y587971D01*
X484409Y587825D01*
G03X486438Y585796I1329J-700D01*
G01X486584Y585873D01*
X486908Y585824D01*
X490613Y582119D01*
G02X490207Y580458I-707J-707D01*
G03X492091Y578574I451J-1433D01*
G02X493752Y578980I954J-301D01*
G01X495220Y577512D01*
X499419D01*
X499549Y577420D01*
G03X501289I870J1224D01*
G01X501419Y577512D01*
X514840D01*
X541730Y550622D01*
Y541627D01*
X541242Y541137D01*
X541068Y541117D01*
G03Y538133I170J-1492D01*
G01X541242Y538113D01*
X541730Y537623D01*
Y531603D01*
G02X541308Y531109I-500J0D01*
G01X541307D01*
G03X540047Y529440I231J-1484D01*
G01X540049Y529426D01*
X540051Y529393D01*
G02X539906Y529007I-499J-33D01*
G01X539450Y528551D01*
X536903D01*
G02X535903Y529555I0J1000D01*
G03X532900Y529505I-1502J6D01*
G02X531901Y528467I-999J-38D01*
G01X529639D01*
G02X528640Y529490I1J1000D01*
G03X525904Y530381I-1502J35D01*
G02X524625Y530061I-822J569D01*
G03X522903Y529813I-686J-1336D01*
G01X522756Y529673D01*
X522349Y529678D01*
X516500Y535526D01*
X493131D01*
X490615Y538042D01*
G02X490779Y539588I707J707D01*
G03X489202Y542144I-816J1261D01*
G01X489084Y542076D01*
X488305D01*
G02X487805Y542576I0J500D01*
G01Y542727D01*
X487889Y542853D01*
G03X486020Y545055I-1249J834D01*
G02X484648Y545680I-414J911D01*
G03X484228Y544146I-1439J-430D01*
G01X484292Y544206D01*
X484447Y544271D01*
G02X485102Y544005I195J-460D01*
G01X485148Y543897D01*
X485141Y543780D01*
G03X485162Y543421I1499J-92D01*
G02X484178Y542244I-984J-177D01*
G01X479018D01*
G02X478665Y542390I0J500D01*
G01X464146Y556909D01*
Y559523D01*
X458370Y565300D01*
X455963D01*
G02X455610Y565446I0J500D01*
G01X448086Y572970D01*
X386445D01*
X386193Y572717D01*
G02X385839Y572570I-354J353D01*
G01X384005D01*
X372779Y561344D01*
X371552D01*
X353664Y543456D01*
Y540395D01*
G02X353517Y540042I-500J1D01*
G01X351020Y537545D01*
Y533748D01*
G37*
G36*
G01X147800Y242219D02*
G03I-640J0D01*
G37*
G36*
G01X158210Y660136D02*
Y646724D01*
X184730D01*
Y660136D01*
X158210D01*
G37*
G36*
G01X219976Y269487D02*
G02X219489Y269872I0J500D01*
G03X218154Y270950I-1364J-323D01*
G01X217976Y270954D01*
X217616Y271260D01*
X217582Y271431D01*
G03X217038Y272319I-1473J-292D01*
G02Y272959I947J320D01*
G03X216746Y275499I-929J1180D01*
G01X216667Y275536D01*
X215181Y277022D01*
X202010D01*
G02X201010Y278029I0J1000D01*
G03X198008I-1501J65D01*
G02X197008Y277022I-1000J-7D01*
G01X193397D01*
G02X192410Y277864I0J1000D01*
G03X189426I-1492J-177D01*
G02X188439Y277022I-987J158D01*
G01X188276D01*
G02X187363Y278429I0J1000D01*
G03X187286Y279802I-1372J612D01*
G03X186662Y280385I-1295J-761D01*
G03X184842Y280009I-671J-1344D01*
G03X184080Y279625I220J-1385D01*
G02X183839Y279452I-697J717D01*
G01X183588Y279485D01*
X183561Y279492D01*
G03X183556Y279493I-297J-1473D01*
G03X183167Y279536I-358J-1459D01*
G03X183054Y279530I23J-1502D01*
G01X183036Y279528D01*
X182999Y279527D01*
G02X182632Y279673I-14J500D01*
G01X176915Y285390D01*
G02X176796Y285908I353J354D01*
G01X176829Y286005D01*
X176876Y286067D01*
G03X176902Y286102I-1210J926D01*
G01X176969Y286196D01*
X177129Y286284D01*
G02X177567Y286303I238J-440D01*
G01X177703Y286244D01*
X177768Y286181D01*
G03X178571Y285780I1042J1082D01*
G03X179628Y288523I239J1483D01*
G03X177802Y288377I-818J-1260D01*
G03X177762Y288339I1014J-1108D01*
G02X176644Y288147I-698J716D01*
G03X176153Y288426I-985J-1163D01*
G01X176118Y288445D01*
Y289378D01*
X175441Y290055D01*
X175412Y290100D01*
G03X175298Y290256I-1267J-806D01*
G03X175065Y290479I-1149J-968D01*
G01X174972Y290551D01*
X174870Y290758D01*
Y291943D01*
G02X175318Y292440I500J0D01*
G03X176492Y293236I-156J1494D01*
G02X177068Y293486I443J-232D01*
G03X178154Y293596I402J1447D01*
G03X178549Y293888I-683J1337D01*
G02X179245Y293911I360J-347D01*
G03X181744Y295211I1009J1112D01*
G03X179175Y296068I-1490J-188D01*
G02X178479Y296045I-360J347D01*
G03X176228Y295778I-1009J-1112D01*
G03X176140Y295631I1243J-844D01*
G02X175564Y295381I-443J232D01*
G03X175413Y295415I-405J-1446D01*
G03X175318Y295428I-251J-1481D01*
G02X174870Y295925I52J497D01*
G01Y303148D01*
G02X175348Y303648I501J0D01*
G01X182291D01*
G02X183255Y302749I-31J-1000D01*
G03X186253I1499J94D01*
G02X187217Y303648I995J-101D01*
G01X192345D01*
G02X193298Y302470I-31J-1000D01*
G03X196244I1473J-294D01*
G02X197197Y303648I984J178D01*
G01X199564D01*
X199920Y304003D01*
X200213Y304296D01*
X203301D01*
G02X204300Y303255I0J-1000D01*
G03Y303056I1999J-100D01*
G03X206299Y301146I1999J91D01*
G01X207373D01*
X209467Y303240D01*
G02X211143Y302779I707J-707D01*
G03X211432Y302202I1456J368D01*
G02Y300944I-777J-629D01*
G03X213766I1167J-946D01*
G02Y302202I777J629D01*
G03X214079Y303402I-1167J945D01*
G03X212141Y304579I-1480J-254D01*
G02X211635Y304701I-153J476D01*
G02Y305408I354J353D01*
G01X211842Y305615D01*
Y307529D01*
X215800Y311487D01*
X217246D01*
X217532Y311202D01*
X217533Y311201D01*
G03X217646Y311096I1418J1412D01*
G01X217725Y311029D01*
X217916Y310639D01*
X217888Y310559D01*
G03X217440Y309806I1011J-1111D01*
G03X217458Y309023I1459J-358D01*
G03X220116Y308568I1441J425D01*
G02X220832I358J-934D01*
G03X223266I1217J880D01*
G02X223982I358J-934D01*
G03Y310328I1217J880D01*
G02X223266I-358J934D01*
G03X223118Y310504I-1220J-876D01*
G03X223051Y310567I-1062J-1062D01*
G01X222869Y310729D01*
X222844Y311140D01*
X222973Y311409D01*
X223049Y311476D01*
G03X223550Y312533I-1000J1121D01*
G02X224549Y313489I999J-44D01*
G01X227050D01*
X228748Y315187D01*
X245815D01*
X245897Y315142D01*
G03X247825Y314327I1384J585D01*
G02X248618Y313349I-207J-978D01*
G01Y310317D01*
X250790Y308145D01*
Y305093D01*
X254121Y301762D01*
G02X253782Y300125I-707J-707D01*
G03X253867Y297300I552J-1397D01*
G03X255572Y299579I467J1428D01*
G02X256408Y301128I836J549D01*
G01X260489D01*
G02X260845Y300979I0J-500D01*
G03X262985I1070J1054D01*
G02X263341Y301128I356J-351D01*
G01X265141D01*
X265414Y300855D01*
X266224Y301665D01*
G02X266668Y301804I354J-353D01*
G03X266902Y301779I276J1476D01*
G03X266954I26J1502D01*
G03X267185Y301799I-14J1502D01*
G03X267212Y301804I-260J1479D01*
G03X267692Y301981I-272J1477D01*
G01X268013Y301923D01*
X270873Y299062D01*
X329980D01*
X330176Y298973D01*
X330247Y298892D01*
G03X330874Y298467I1129J990D01*
G03X332796Y300373I502J1416D01*
G03X332781Y300414I-1418J-496D01*
G02X333729Y301734I947J320D01*
G01X344280D01*
X345584Y303038D01*
X345999D01*
X346182Y302963D01*
X346275Y302869D01*
X346316Y302828D01*
X346440Y302704D01*
X349641D01*
X349878Y302536D01*
G02X350005Y301941I-868J-496D01*
G03X352995I1495J-146D01*
G02X353122Y302536I995J99D01*
G01X353359Y302704D01*
X363091D01*
X364957Y300839D01*
X365550Y300246D01*
G03X365569Y300227I1071J1052D01*
G01X366083Y299713D01*
X366084Y299712D01*
X366488Y299308D01*
X366489Y299307D01*
X367308Y298488D01*
X370275D01*
X370926Y299139D01*
X371443Y299655D01*
X373762Y301974D01*
Y308400D01*
X372652Y309509D01*
X370549Y311613D01*
X369990Y312172D01*
X369876Y312445D01*
X368759Y313562D01*
G02X369286Y315253I707J707D01*
G03X367558Y316981I-246J1482D01*
G02X365867Y316454I-984J180D01*
G01X364682Y317640D01*
Y334109D01*
G02X365182Y334609I500J0D01*
G01X372128D01*
X372380Y334357D01*
X467645D01*
G02X468622Y333144I0J-1000D01*
G03X471558I1468J-320D01*
G02X472535Y334357I977J213D01*
G01X478829D01*
G02X479329Y333873I0J-500D01*
G03X482331I1501J48D01*
G02X482831Y334357I500J-16D01*
G01X531233D01*
X533175Y336299D01*
G02X534796Y335996I707J-708D01*
G03X536777Y337977I1374J607D01*
G02X536474Y339598I405J914D01*
G01X586489Y389613D01*
X599830D01*
X599840Y389602D01*
X603360D01*
X606482Y392724D01*
X606505Y392742D01*
G03X606751Y392988I-932J1178D01*
G01X606769Y393011D01*
X606883Y393125D01*
G02X607590I353J-354D01*
G01X607658Y393056D01*
X607696Y392968D01*
G03X608177Y392355I1382J589D01*
G03X610573Y393705I901J1202D01*
G03X610113Y394646I-1495J-148D01*
G02X610023Y395997I689J724D01*
G03X610256Y396382I-1154J962D01*
G03X610285Y396458I-1388J573D01*
G01X610323Y396565D01*
X610566Y396808D01*
X610567Y396809D01*
G02X610983Y396952I354J-353D01*
G01X611097Y396937D01*
X611291Y396810D01*
X611350Y396710D01*
G03X612936Y396005I1291J768D01*
G03X613698Y398545I-295J1473D01*
G02X613708Y399950I717J697D01*
G01X614210Y400452D01*
Y401895D01*
X614185Y401920D01*
X614110Y402144D01*
X614127Y402262D01*
G03X613413Y403766I-1486J216D01*
G01X613300Y403834D01*
X613170Y404063D01*
Y422466D01*
X614027Y423323D01*
G02X614881Y422970I354J-353D01*
G01Y422818D01*
X614850Y422734D01*
G03X614823Y421768I1408J-523D01*
G03X617117Y420979I1435J443D01*
G03X617217Y421055I-858J1233D01*
G03X616865Y423585I-959J1156D01*
G03X616547Y423685I-607J-1374D01*
G02X616070Y425366I230J973D01*
G01X618987Y428283D01*
X629910D01*
X630890Y429263D01*
X631186D01*
G02X632097Y427851I0J-1000D01*
G03X632015Y427638I1357J-645D01*
G03X631996Y426853I1440J-428D01*
G03X632425Y426116I1459J356D01*
G03X632725Y425896I1031J1092D01*
G01X632835Y425835D01*
X633124Y425385D01*
X633094Y425197D01*
G03X635308Y426277I1484J-233D01*
G01X635198Y426338D01*
X634910Y426788D01*
X634939Y426975D01*
G03X634950Y427067I-1485J224D01*
G03X634951Y427346I-1495J145D01*
G03X634867Y427722I-1496J-137D01*
G03X634841Y427788I-1410J-517D01*
G03X634813Y427851I-1386J-578D01*
G02X635724Y429263I911J412D01*
G01X640368D01*
X640508Y429144D01*
G03X640530Y429126I962J1153D01*
G03X640533Y429123I1060J1057D01*
G03X640566Y429097I946J1167D01*
G03X641016Y428860I915J1191D01*
G02X641707Y427879I-308J-951D01*
G03X641706Y427787I1501J-62D01*
G03X641720Y427614I1502J34D01*
G03X644701Y427982I1488J206D01*
G03X644682Y428109I-1494J-159D01*
G02X645670Y429263I988J154D01*
G01X645746D01*
G02X646734Y428109I0J-1000D01*
G03X648304Y426320I1474J-290D01*
G02X649320Y425310I16J-1000D01*
G03X651784Y424141I1502J-16D01*
G03X652318Y425165I-962J1153D01*
G03X651748Y426478I-1496J131D01*
G03X650998Y426787I-926J-1183D01*
G03X650726Y426794I-174J-1492D01*
G02X649710Y427804I-16J1000D01*
G03Y427848I-1502J22D01*
G02X650458Y428835I1000J19D01*
G03X650972Y429081I-380J1454D01*
G03X651004Y429105I-885J1214D01*
G03X651051Y429144I-936J1175D01*
G01X651191Y429263D01*
X653551D01*
G02X654538Y428104I0J-1000D01*
G03X654894Y426871I1483J-240D01*
G03X654974Y426787I1127J993D01*
G02X654886Y425289I-704J-710D01*
G03X654315Y423978I926J-1183D01*
G03X656735Y422921I1497J128D01*
G03X657190Y423508I-923J1185D01*
G02X658200Y424105I917J-398D01*
G03X659012Y424258I139J1496D01*
G03X658421Y427101I-673J1343D01*
G02X657520Y427966I91J996D01*
G03X657506Y428091I-1499J-105D01*
G03X657504Y428104I-1485J-222D01*
G02X658491Y429263I987J159D01*
G01X663295D01*
G02X664285Y428120I0J-1000D01*
G03X664274Y428042I1481J-249D01*
G03X664268Y427983I1491J-181D01*
G02X663301Y427103I-993J120D01*
G03X662258Y424558I38J-1502D01*
G03X663476Y424105I1081J1043D01*
G03X664837Y425486I-137J1496D01*
G02X665804Y426366I993J-120D01*
G03X667202Y427426I-38J1502D01*
G03X667247Y428120I-1436J442D01*
G02X668237Y429263I990J143D01*
G01X669468D01*
X669974Y428757D01*
G02X669994Y427362I-707J-708D01*
G03X672118Y425238I1062J-1062D01*
G02X673513Y425218I687J-727D01*
G01X674000Y424731D01*
X678369D01*
X686550Y416550D01*
Y415073D01*
X686369Y414815D01*
X686220Y414761D01*
G03Y411937I511J-1412D01*
G01X686369Y411883D01*
X686550Y411625D01*
Y408696D01*
G02X686317Y408273I-500J0D01*
G03X685696Y406528I804J-1269D01*
G02X685192Y405316I-948J-316D01*
G03X685674Y402479I667J-1346D01*
G02X686550Y401487I-124J-992D01*
G01Y399258D01*
X686362Y398998D01*
X686209Y398946D01*
G03Y396098I477J-1424D01*
G01X686362Y396046D01*
X686550Y395786D01*
Y394420D01*
G02X686209Y393946I-500J0D01*
G03Y391098I477J-1424D01*
G02X686550Y390624I-159J-474D01*
G01Y387507D01*
X686504Y387407D01*
G03Y386153I1365J-627D01*
G01X686550Y386053D01*
Y383571D01*
X679351Y376372D01*
G02X678020Y376298I-707J707D01*
G03X675909Y374187I-937J-1174D01*
G02X675835Y372856I-781J-624D01*
G01X674016Y371037D01*
X650473D01*
G02X649655Y372611I1J1000D01*
G03X647195I-1230J863D01*
G02X646377Y371037I-819J-574D01*
G01X604450D01*
X532022Y298609D01*
X483267D01*
X461370Y276712D01*
Y255341D01*
G02X459866Y254478I-1000J1D01*
G03X459047Y254682I-758J-1297D01*
G02X458017Y255822I-40J999D01*
G03X458025Y256180I-1487J212D01*
G03X455780Y257336I-1495J-146D01*
G03X456591Y254533I749J-1302D01*
G02X457621Y253393I40J-999D01*
G03X459866Y251884I1487J-212D01*
G02X461370Y251021I504J-864D01*
G01Y248403D01*
G02X460218Y247415I-1000J0D01*
G03Y244445I-228J-1485D01*
G02X461370Y243457I152J-988D01*
G01Y239957D01*
X460081Y238668D01*
X445356D01*
G02X444492Y240170I1J1000D01*
G03X441932I-1280J787D01*
G02X441068Y238668I-865J-502D01*
G01X394630D01*
X375186Y258112D01*
X344901D01*
X331822Y271191D01*
X283868D01*
G02X283479Y271377I0J500D01*
G03X282859Y271833I-1170J-942D01*
G01X282726Y271885D01*
X282380Y272349D01*
X282387Y272526D01*
G03X282314Y273054I-1501J62D01*
G03X279968Y273776I-1428J-467D01*
G02X278804I-582J813D01*
G03X276968I-918J-1189D01*
G02X275804I-582J813D01*
G03X273968I-918J-1189D01*
G02X272804I-582J813D01*
G03X270968I-918J-1189D01*
G02X269804I-582J813D01*
G03X267651Y273442I-918J-1189D01*
G02X266460Y273106I-809J588D01*
G03X264786Y272741I-574J-1388D01*
G02X263661Y272502I-732J681D01*
G03X263440Y272584I-631J-1363D01*
G03X262808Y272625I-411J-1445D01*
G03X262514Y272550I222J-1486D01*
G03X261968Y272203I514J-1412D01*
G03X261871Y272096I1063J-1061D01*
G03X261627Y271679I1158J-957D01*
G01X261576Y271546D01*
X261105Y271191D01*
X259193D01*
X258718Y271561D01*
X258669Y271699D01*
G03X258462Y272089I-1416J-502D01*
G03X258171Y272386I-1208J-893D01*
G03X257853Y272574I-918J-1189D01*
G03X257181Y272697I-599J-1377D01*
G02X256670Y273086I-23J500D01*
G03X255277Y271255I-1465J-331D01*
G02X255788Y270866I23J-500D01*
G03X255797Y270829I1464J336D01*
G03X255799Y270819I1473J289D01*
G03X255807Y270790I1452J385D01*
G03X256007Y270356I1447J404D01*
G01X256046Y270298D01*
X256094Y270149D01*
G02X255972Y269641I-476J-154D01*
G01X255818Y269487D01*
X248059D01*
X247967Y269525D01*
G03X246811I-578J-1386D01*
G01X246719Y269487D01*
X243908D01*
G02X242909Y270437I0J1000D01*
G03X242047Y272635I-1296J760D01*
G02X241860Y273578I767J642D01*
G03X242353Y275160I-950J1164D01*
G03X240891Y276244I-1443J-418D01*
G03X240719Y276232I18J-1502D01*
G03X239892Y275846I192J-1490D01*
G03X239884Y275839I984J-1133D01*
G03X239708Y275643I1025J-1098D01*
G03X240476Y273304I1202J-901D01*
G02X240663Y272361I-767J-642D01*
G03X240450Y272148I950J-1163D01*
G03X240190Y271678I1163J-950D01*
G03X240164Y271593I1423J-482D01*
G03X240153Y271551I1447J-402D01*
G03X240148Y271529I1462J-344D01*
G02X239638Y271139I-488J110D01*
G03X238090Y269900I-69J-1500D01*
G02X237597Y269487I-492J87D01*
G01X235774D01*
G02X235279Y269915I0J500D01*
G03X234175Y271149I-1486J-218D01*
G01X234029Y271188D01*
X233627Y271642D01*
X233606Y271792D01*
G03X233107Y272718I-1488J-204D01*
G01X233032Y272784D01*
X232840Y273173D01*
X232915Y273433D01*
X232978Y273543D01*
X232997Y273581D01*
G03X233114Y273917I-1350J659D01*
G03X233107Y274598I-1466J325D01*
G03X232462Y275506I-1460J-354D01*
G03X230494Y275205I-814J-1263D01*
G02X229942Y275197I-290J957D01*
G03X228235Y275580I-1121J-1000D01*
G03X228512Y272727I586J-1383D01*
G03X229975Y273235I309J1470D01*
G02X230527Y273243I290J-957D01*
G03X230659Y273112I1122J999D01*
G01X230734Y273046D01*
X230926Y272657D01*
X230850Y272394D01*
X230819Y272341D01*
G03X230816Y272335I1339J-673D01*
G03X230752Y272213I1297J-758D01*
G03X230620Y271698I1366J-625D01*
G03X230616Y271600I1498J-110D01*
G03X230975Y270612I1502J-13D01*
G02X229983Y269487I-992J-125D01*
G01X219976D01*
G37*
G36*
G01X242562Y319868D02*
G03X239954I-1304J-745D01*
G02X239520Y319616I-434J248D01*
G01X230161D01*
X229914Y319863D01*
Y323154D01*
G02X230838Y324151I1000J0D01*
G03Y327147I-113J1498D01*
G02X229914Y328144I76J997D01*
G01Y329154D01*
G02X230838Y330151I1000J0D01*
G03X232190Y331317I-113J1498D01*
G02X232701Y331707I488J-110D01*
G03X233956Y332286I69J1500D01*
G03X233970Y334110I-1187J921D01*
G02X233987Y335256I828J561D01*
G03X233856Y337253I-1183J925D01*
G02X233944Y338725I719J696D01*
G03X234538Y339695I-889J1211D01*
G03X234372Y340658I-1483J240D01*
G03X234371Y340660I-1344J-671D01*
G03X232454Y341313I-1316J-724D01*
G03X231812Y340779I602J-1376D01*
G03X231569Y340153I1243J-843D01*
G02X231092Y339726I-495J73D01*
G03X231021Y339722I49J-1501D01*
G03X231006Y339721I92J-1499D01*
G02X229914Y340716I-92J996D01*
G01Y356706D01*
X229916Y356728D01*
G03Y356982I-1497J127D01*
G01X229914Y357004D01*
Y359740D01*
G02X231051Y360730I1000J0D01*
G03Y363706I206J1488D01*
G02X229914Y364696I-137J990D01*
G01Y365198D01*
G02X230115Y365799I1000J0D01*
G01Y367493D01*
X229196Y368412D01*
X229158Y368517D01*
G03X228255Y369420I-1413J-510D01*
G01X228150Y369458D01*
X224609Y372999D01*
X197097D01*
G02X196678Y373226I0J500D01*
G03X194162I-1258J-820D01*
G02X193743Y372999I-419J273D01*
G01X181308D01*
X177555Y376752D01*
X177524Y376894D01*
G03X176384Y378034I-1466J-326D01*
G01X176242Y378065D01*
X176135Y378172D01*
G02X176168Y379618I707J707D01*
G03X176057Y381928I-1013J1109D01*
G01X175970Y381993D01*
X175782Y382340D01*
X175780Y382586D01*
X175836Y382696D01*
G03X175914Y383888I-1336J686D01*
G02X176379Y385104I942J337D01*
G03X176703Y387508I-716J1320D01*
G02X176554Y388770I692J722D01*
G03X174250Y388498I-1264J812D01*
G02X174399Y387236I-692J-722D01*
G03X174249Y385919I1264J-811D01*
G02X173784Y384703I-942J-337D01*
G03X173017Y383623I716J-1321D01*
G02X171323Y383075I-987J159D01*
G01X170472Y383927D01*
Y402100D01*
X173883Y405512D01*
X174020Y405722D01*
G03X174023Y405727I-1286J775D01*
G01X174055Y405780D01*
X174378Y406103D01*
X178280D01*
X185455Y398928D01*
X199560D01*
X199765Y399133D01*
X213398D01*
G02X213827Y398889I0J-500D01*
G01X213828Y398888D01*
G03X216355Y398799I1292J766D01*
G01X216420Y398892D01*
X216842Y399133D01*
X257099D01*
X261418Y394814D01*
Y393450D01*
G03X264480Y391753I2001J0D01*
G01X264737Y391495D01*
X266057Y390175D01*
X266094Y390061D01*
G03X266100Y390044I1890J657D01*
G03X266110Y390016I1890J659D01*
G03X266114Y390007I1828J807D01*
G01X266152Y389908D01*
X266142Y389700D01*
X265979Y389369D01*
X265902Y389303D01*
G03X265431Y388554I980J-1139D01*
G03X267431Y386767I1451J-389D01*
G03X268263Y387575I-549J1398D01*
G02X268723Y387878I460J-197D01*
G01X268934D01*
G02X269434Y387378I0J-500D01*
G01Y387283D01*
X269399Y387194D01*
G03X269301Y386791I1397J-553D01*
G03X269303Y386477I1495J-147D01*
G03X269332Y386307I1493J167D01*
G03X269621Y385707I1464J335D01*
G03X271092Y385170I1175J936D01*
G03X272289Y386811I-296J1473D01*
G02X273287Y387878I998J67D01*
G01X293916D01*
X294232Y387562D01*
Y383837D01*
X294220Y383824D01*
Y381659D01*
G02X293720Y381159I-500J0D01*
G01X285096D01*
X280138Y376201D01*
G02X278475Y376614I-707J707D01*
G03X276598Y374737I-1435J-442D01*
G02X277011Y373074I-294J-956D01*
G01X259801Y355864D01*
X259607Y355788D01*
X259502Y355792D01*
G03X257943Y354233I-58J-1501D01*
G02X257797Y353860I-500J-20D01*
G01X248716Y344779D01*
Y341187D01*
X248296Y340702D01*
X248143Y340664D01*
G03X247928Y340593I362J-1458D01*
G01X247885Y340575D01*
X247788Y340554D01*
G02X247197Y340942I-101J490D01*
G01X247182Y341014D01*
X247188Y341087D01*
G03X245109Y339830I-1497J128D01*
G02X245522Y338308I-387J-922D01*
G03X245673Y336247I1163J-951D01*
G03X247304Y335988I1012J1110D01*
G02X248716Y335077I412J-911D01*
G01Y334785D01*
G02X248216Y334285I-500J0D01*
G01X248082D01*
X247966Y334351D01*
G03X245954Y332236I-749J-1302D01*
G01X245990Y332180D01*
X246080Y331898D01*
X245943Y331557D01*
X245888Y331494D01*
G03X247440Y329068I1137J-982D01*
G02X248716Y328107I276J-961D01*
G01Y325911D01*
G02X247740Y324911I-1000J0D01*
G03X246964Y324734I48J-2001D01*
G03X245788Y322910I825J-1823D01*
G01Y322074D01*
X246610Y321252D01*
G02X245838Y319616I-772J-636D01*
G01X242996D01*
G02X242562Y319868I0J500D01*
G37*
G36*
G01X257139Y549899D02*
G02X258139Y550911I1000J12D01*
G01X265806D01*
G02X266806Y549900I0J-1000D01*
G03X267075Y548988I1466J-63D01*
G03X267897Y548418I1197J848D01*
G03X269235Y548729I376J1418D01*
G02X270458I612J-792D01*
G03X271796Y548418I962J1107D01*
G03X272618Y548988I-375J1418D01*
G03X272887Y549900I-1197J849D01*
G02X273887Y550911I1000J11D01*
G01X274484Y551508D01*
X274671Y551521D01*
G03X275197Y551658I-100J1464D01*
G03X275618Y551958I-627J1326D01*
G01X275683Y552024D01*
X276054Y552193D01*
X276353D01*
X276549Y552104D01*
X276621Y552022D01*
G03X278770Y551959I1104J967D01*
G01X278835Y552025D01*
X279205Y552193D01*
X279393D01*
G02X279769Y552023I0J-500D01*
G01X279770Y552022D01*
G03X279993Y551815I1105J966D01*
G02X279992Y551015I-300J-400D01*
G03X281095Y548391I880J-1174D01*
G03X281826Y550955I-223J1450D01*
G01X281750Y551021D01*
X281665Y551190D01*
G02Y551637I447J224D01*
G01X281751Y551807D01*
X281827Y551873D01*
G03X281918Y551958I-955J1114D01*
G01X281984Y552025D01*
X282354Y552193D01*
X282652D01*
X282848Y552104D01*
X282920Y552022D01*
G03X285069Y551959I1104J967D01*
G01X285134Y552025D01*
X285504Y552193D01*
X285693D01*
G02X286069Y552023I0J-500D01*
G01X286070Y552022D01*
G03X288219Y551959I1104J967D01*
G01X288284Y552025D01*
X288654Y552193D01*
X289659D01*
G02X289828Y551222I1J-500D01*
G03X290168Y548382I494J-1381D01*
G03X291709Y550319I154J1459D01*
G03X291545Y550651I-1387J-479D01*
G02X292386Y552193I840J542D01*
G01X310667D01*
G02X311656Y551044I0J-1000D01*
G03X314626I1485J-223D01*
G02X315615Y552193I989J149D01*
G01X326365D01*
X329910Y548648D01*
Y535866D01*
G02X329085Y534882I-1000J1D01*
G03Y531924I263J-1479D01*
G02X329910Y530940I-175J-985D01*
G01Y524132D01*
X325520Y519742D01*
X325456Y519707D01*
G03X324849Y519100I714J-1321D01*
G01X324814Y519036D01*
X320024Y514246D01*
X319860Y514222D01*
G03X318594Y512956I220J-1486D01*
G01X318570Y512792D01*
X315000Y509222D01*
Y502113D01*
X304910Y492023D01*
X269380D01*
X269141Y492169D01*
X269077Y492294D01*
G03X268088Y493069I-1336J-686D01*
G03X266789Y492770I-348J-1461D01*
G03X266632Y492621I953J-1161D01*
G02X265107Y492680I-738J675D01*
G03X262775Y492721I-1183J-926D01*
G03X262481Y492171I1149J-968D01*
G03X262716Y490861I1443J-417D01*
G02X261893Y489293I-823J-568D01*
G01X225920D01*
G02X225420Y489793I0J500D01*
G01Y490954D01*
X225493Y491073D01*
G03X225440Y492713I-1284J779D01*
G03X225394Y492776I-1235J-854D01*
G02Y494005I789J615D01*
G03X223024I-1185J923D01*
G02Y492776I-789J-615D01*
G03X222707Y491824I1185J-923D01*
G02X221908Y490825I-1000J-20D01*
G03X221629Y490738I305J-1470D01*
G03X221432Y490639I574J-1388D01*
G03X221323Y490566I781J-1283D01*
G02X220195I-564J826D01*
G03X219439Y490849I-885J-1213D01*
G03X218180Y490343I-130J-1496D01*
G02X216953Y490158I-730J683D01*
G03X216436Y490338I-744J-1305D01*
G03X215291Y490042I-227J-1485D01*
G02X214127I-582J813D01*
G03X213169Y490354I-917J-1189D01*
G03X211860Y489514I39J-1501D01*
G03X211767Y488432I1349J-661D01*
G01X211776Y488400D01*
X211788Y488322D01*
G02X211647Y487892I-494J-76D01*
G01X210340Y486585D01*
X210339D01*
X209698Y485943D01*
X209302Y485547D01*
X197572D01*
X194802Y488316D01*
G02X194742Y488951I353J354D01*
G03X193946Y491230I-1242J845D01*
G01X193789Y491279D01*
X193595Y491543D01*
Y498774D01*
X208108Y513287D01*
X212102D01*
X212222Y513407D01*
X228036D01*
G02X229031Y512304I0J-1000D01*
G01X229026Y512260D01*
X229025Y512254D01*
G03X230748Y510599I1451J-214D01*
G03X231413Y510911I-271J1442D01*
G02X232689I638J-770D01*
G03X232695Y510906I941J1124D01*
G03X232747Y510866I920J1142D01*
G02Y510065I-300J-400D01*
G03X232160Y508831I879J-1175D01*
G03X232912Y507609I1466J60D01*
G03X234563Y507762I714J1282D01*
G02X235839I638J-770D01*
G03X236216Y507535I937J1129D01*
G03X237885Y509851I560J1356D01*
G02Y511080I790J615D01*
G03X238237Y511908I-1109J960D01*
G03X238059Y512752I-1461J133D01*
G03X237905Y512977I-1282J-712D01*
G02Y514253I770J638D01*
G03X238150Y514675I-1129J937D01*
G02X238618Y515000I468J-175D01*
G01X243004D01*
X244126Y516122D01*
X244509Y516141D01*
X244659Y516019D01*
G03X245581Y515680I951J1163D01*
G03X245626I22J1502D01*
G03X246763Y516220I-17J1502D01*
G03X247053Y517596I-1154J962D01*
G03X246792Y518108I-1444J-414D01*
G03X246488Y518400I-1182J-927D01*
G03X246233Y518548I-878J-1219D01*
G01X246151Y518586D01*
X245468Y519269D01*
Y549531D01*
X246848Y550911D01*
X250058D01*
G02X251058Y549899I0J-1000D01*
G03X251327Y548987I1466J-63D01*
G03X252149Y548417I1197J848D01*
G03X253487Y548728I376J1418D01*
G02X254710I612J-792D01*
G03X256048Y548417I962J1107D01*
G03X256870Y548987I-375J1418D01*
G03X257139Y549899I-1197J849D01*
G37*
G36*
G01X206844Y98370D02*
G03I-594J0D01*
G37*
G36*
G01X215256Y459653D02*
X215210Y459699D01*
X206510D01*
G02X206010Y460199I0J500D01*
G01Y462001D01*
X206029Y462068D01*
G03Y462888I-1445J410D01*
G01X206010Y462955D01*
Y471599D01*
G02X206510Y472099I500J0D01*
G01X220810D01*
G02X221310Y471599I0J-500D01*
G01Y460153D01*
G02X220810Y459653I-500J0D01*
G01X215256D01*
G37*
G36*
G01X215174Y93749D02*
G03I-594J0D01*
G37*
G36*
G01X236961Y93909D02*
G03I-594J0D01*
G37*
G36*
G01X235791Y96883D02*
G03I-594J0D01*
G37*
G36*
G01X283330Y678366D02*
X281991Y677027D01*
G02X280708Y676916I-707J707D01*
G03X278615Y674823I-865J-1228D01*
G02X278504Y673540I-818J-576D01*
G01X278175Y673211D01*
G02X277468I-353J354D01*
G01X277427Y673252D01*
X277386Y673317D01*
X277370Y673341D01*
G03X276332Y673996I-1251J-832D01*
G01X276205Y674014D01*
X275782Y674332D01*
X275729Y674449D01*
G03X274267Y672332I-1369J-618D01*
G02X274706Y672002I-32J-499D01*
G03X275040Y671465I1414J507D01*
G02X275028Y670064I-720J-694D01*
G01X271869Y666905D01*
G02X271244Y666838I-354J353D01*
G03X269168Y664762I-814J-1262D01*
G01X269264Y664613D01*
X269226Y664262D01*
X269101Y664137D01*
X261860Y656896D01*
Y629773D01*
G02X261360Y629273I-500J0D01*
G01X251040D01*
X250810Y629405D01*
X250743Y629521D01*
G03X249013Y630516I-1730J-1006D01*
G01X246084D01*
G02X245128Y631811I-1J1000D01*
G03X242513Y631325I-1435J443D01*
G01X242620Y631189D01*
Y631016D01*
G02X242120Y630516I-500J0D01*
G01X241932D01*
X240689Y629273D01*
X238494D01*
X238074Y629510D01*
X238009Y629603D01*
G03X235551I-1229J-865D01*
G01X235486Y629510D01*
X235066Y629273D01*
X230763D01*
G02X229775Y630121I0J1000D01*
G03X228476Y631384I-1485J-228D01*
G01X228303Y631405D01*
X227821Y631895D01*
Y639707D01*
G02X228972Y640695I1000J0D01*
G03Y643665I227J1485D01*
G02X227821Y644653I-151J988D01*
G01Y650285D01*
G02X229126Y651238I1000J0D01*
G03X230751Y651723I458J1430D01*
G02X232350Y651663I777J-630D01*
G03X234804Y651643I1234J856D01*
G02X236350Y651740I813J-583D01*
G03X236231Y653637I1101J1021D01*
G02X234685Y653540I-813J583D01*
G03X232417Y653464I-1101J-1021D01*
G02X230818Y653524I-777J630D01*
G03X229126Y654098I-1234J-856D01*
G02X227821Y655051I-305J953D01*
G01Y669412D01*
G02X229250Y670315I1000J0D01*
G03Y673029I645J1357D01*
G02X227821Y673932I-429J903D01*
G01Y695329D01*
G02X228321Y695829I500J0D01*
G01X237308D01*
G02X237751Y695560I0J-500D01*
G03X238105Y695113I1333J692D01*
G03X238612Y694826I979J1139D01*
G02X239181Y693410I-315J-949D01*
G03X241107Y691307I1312J-732D01*
G03X240965Y694104I-614J1371D01*
G02X240396Y695520I315J949D01*
G03X240415Y695556I-1319J719D01*
G02X240860Y695829I445J-227D01*
G01X263668D01*
G02X264668Y694828I0J-1000D01*
G03Y694810I1502J-9D01*
G03X266952Y693543I1502J16D01*
G03X266611Y696262I-782J1283D01*
G02X266198Y697925I294J956D01*
G01X269305Y701033D01*
G02X269659Y701180I354J-353D01*
G01X271077D01*
G02X272030Y700007I-32J-1000D01*
G03X274990I1480J-258D01*
G02X275975Y701178I985J171D01*
G01X280730D01*
X283330Y698578D01*
Y678366D01*
G37*
G36*
G01X323287Y367458D02*
G02X322790Y367903I0J500D01*
G03X319804I-1493J-164D01*
G01X319783Y367712D01*
X319499Y367458D01*
X317334D01*
X317215Y367339D01*
G02X316508I-354J354D01*
G01X316366Y367482D01*
X316362Y367684D01*
G03X313412Y368054I-1502J-28D01*
G03X313365Y367800I1448J-399D01*
G02X312403Y366912I-994J112D01*
G01X311174D01*
X310523Y366262D01*
X309953Y365692D01*
X305199Y360938D01*
X305068Y360904D01*
G03X304056Y360020I378J-1454D01*
G03X304306Y358471I1390J-570D01*
G02X304251Y357160I-781J-624D01*
G01X303893Y356801D01*
X296694Y349603D01*
G02X295466Y349527I-663J749D01*
G03X294857Y349770I-848J-1240D01*
G03X293420Y349193I-239J-1483D01*
G03X293350Y349093I1195J-911D01*
G03X293118Y348363I1268J-805D01*
G01X293108Y348163D01*
X292819Y347888D01*
X289039D01*
X284568Y343417D01*
Y339941D01*
X284499Y339823D01*
G03X284353Y339487I1294J-762D01*
G03X284340Y339440I1441J-424D01*
G03X284293Y338996I1454J-378D01*
G03X284327Y338740I1501J69D01*
G03X285022Y337774I1467J322D01*
G02X285258Y336252I-513J-859D01*
G01X284823Y335817D01*
X284446Y335440D01*
X283955Y334949D01*
G02X283422Y334836I-353J354D01*
G01X283247Y334904D01*
X283185Y334954D01*
G03X281245Y334922I-951J-1162D01*
G02X280616Y334898I-329J376D01*
G03X280590Y334917I-899J-1203D01*
G03X278935Y334976I-872J-1223D01*
G01X278711Y335086D01*
X278483Y335198D01*
X278417Y335273D01*
G03X276770Y335692I-1129J-991D01*
G03X276395Y335490I518J-1410D01*
G03X276233Y335351I895J-1207D01*
G03X276171Y335286I1055J-1069D01*
G01X276105Y335213D01*
X275721Y335027D01*
X275470Y335096D01*
X275419Y335124D01*
G03X273986Y335125I-717J-1320D01*
G02X273377Y335229I-238J440D01*
G03X272768Y335637I-1115J-1006D01*
G03X272616Y335682I-502J-1416D01*
G03X272282Y335724I-353J-1460D01*
G01X272281D01*
G02X271793Y336117I0J500D01*
G03X271773Y336197I-1466J-324D01*
G03X271753Y336264I-1449J-396D01*
G03X271654Y336497I-1427J-469D01*
G03X271511Y336718I-1328J-702D01*
G02X271473Y337866I799J601D01*
G03X271995Y338806I-988J1164D01*
G01X272019Y338969D01*
X272440Y339391D01*
X272599Y339418D01*
G03X272848Y339482I-248J1482D01*
G02X274170Y338666I330J-944D01*
G03X275164Y340275I1490J191D01*
G02X273842Y341091I-330J944D01*
G03X270870Y341145I-1490J-191D01*
G01X270844Y340987D01*
X270423Y340565D01*
X270259Y340540D01*
G03X269818Y340403I227J-1510D01*
G02X269375Y340406I-218J450D01*
G01X269149Y340519D01*
X269083Y340595D01*
X269082Y340596D01*
G03X267148Y340892I-1139J-979D01*
G03X266844Y340641I796J-1274D01*
G03X266561Y340205I1099J-1023D01*
G03X267136Y338350I1382J-588D01*
G03X268538Y338238I807J1267D01*
G01X268582Y338256D01*
X268871Y338320D01*
X269246Y338130D01*
X269312Y338051D01*
G03X269387Y337968I1170J982D01*
G02X269241Y336834I-887J-462D01*
G03X269154Y336734I1088J-1035D01*
G03X268861Y336124I1172J-938D01*
G03X269050Y335002I1465J-330D01*
G03X269115Y334906I1275J793D01*
G01X269159Y334846D01*
X269266Y334540D01*
X269095Y334167D01*
X269027Y334101D01*
G03X268931Y332042I1044J-1080D01*
G01X268986Y331979D01*
X269121Y331641D01*
X269059Y331436D01*
G03X268986Y331326I1233J-897D01*
G01X268922Y331218D01*
X268748Y331114D01*
G02X268286Y331086I-258J428D01*
G01X268160Y331142D01*
X268094Y331208D01*
G03X267030Y331649I-1063J-1061D01*
G03X266355Y331489I0J-1502D01*
G03X265559Y330453I675J-1342D01*
G03X265528Y330160I1471J-304D01*
G03Y330144I1502J-8D01*
G03X268145Y329140I1502J2D01*
G02X269303Y329380I743J-670D01*
G03X269647Y329159I989J1161D01*
G01X269727Y329121D01*
X270053Y328795D01*
X270156Y328691D01*
G02X269881Y327111I-726J-688D01*
G03X269770Y327053I640J-1359D01*
G03X269625Y326957I755J-1299D01*
G01X269564Y326911D01*
X269251Y326799D01*
X268917Y326931D01*
X268854Y326984D01*
G03X268272Y327288I-970J-1147D01*
G03X267349Y327241I-389J-1451D01*
G01X267263Y327208D01*
X266800D01*
X266565Y327332D01*
X266499Y327416D01*
G03X266396Y327533I-1177J-933D01*
G03X265333Y327989I-1078J-1046D01*
G03X265150Y327980I-18J-1502D01*
G02X264095Y328725I-87J996D01*
G03X264071Y328807I-1453J-381D01*
G03X264013Y328959I-1430J-459D01*
G03X263894Y329176I-1372J-611D01*
G03X263854Y329233I-1249J-834D01*
G02X264078Y330595I826J564D01*
G03X264390Y330913I-904J1199D01*
G03X264645Y332094I-1217J881D01*
G03X264059Y333007I-1472J-300D01*
G03X264045Y333017I-880J-1217D01*
G02X263691Y334088I607J795D01*
G03X263727Y334245I-1444J414D01*
G02X264169Y334657I493J-85D01*
G03X264317Y334680I-156J1494D01*
G01X264319D01*
G03X264955Y334979I-303J1471D01*
G03X264429Y337595I-940J1172D01*
G01X264282Y337637D01*
X263889Y338106D01*
X263873Y338258D01*
G03X263835Y338472I-1494J-155D01*
G02X264313Y339589I969J246D01*
G03X263983Y342344I-737J1309D01*
G03X262074Y340927I-407J-1446D01*
G03X262120Y340529I1502J-28D01*
G02X261642Y339412I-969J-246D01*
G03X261298Y337060I737J-1309D01*
G02X261245Y335621I-720J-694D01*
G03X261164Y335543I1001J-1120D01*
G03X261018Y333638I1083J-1041D01*
G03X261375Y333279I1228J865D01*
G02X261729Y332208I-607J-795D01*
G03X261716Y332160I1443J-417D01*
G03X261707Y331466I1457J-366D01*
G03X261854Y331075I1466J328D01*
G03X261960Y330908I1318J720D01*
G02X262131Y330412I-827J-562D01*
G01X261779Y329939D01*
X261647Y329887D01*
G03X261180Y327389I554J-1396D01*
G02X261357Y326210I-705J-709D01*
G03X261353Y324787I1343J-715D01*
G02X261042Y323806I-973J-231D01*
G03X260936Y323703I992J-1127D01*
G03X261976Y321178I1099J-1024D01*
G03X262940Y321480I59J1501D01*
G03X263419Y323264I-905J1199D01*
G02X263588Y324259I936J353D01*
G03X264028Y324751I-887J1236D01*
G01X264089Y324860D01*
X264512Y325129D01*
X264795Y325079D01*
X264831Y325066D01*
G03X265737Y325045I486J1421D01*
G03X265742Y325046I-292J1473D01*
G03X265916Y325109I-423J1441D01*
G01X265959Y325128D01*
X266254Y325193D01*
X266636Y324992D01*
X266702Y324908D01*
G03X268032Y324342I1181J929D01*
G03X268784Y324635I-149J1495D01*
G01X268844Y324680D01*
X269157Y324792D01*
X269493Y324660D01*
X269556Y324606D01*
G03X269617Y324557I971J1146D01*
G03X269812Y324432I906J1198D01*
G03X269963Y324361I714J1322D01*
G03X270009Y324343I570J1389D01*
G03X271484Y324598I516J1411D01*
G02X272094Y324620I319J-385D01*
G03X272704Y324363I874J1222D01*
G03X272865Y324343I265J1478D01*
G03X273332Y324385I101J1499D01*
G01X273334D01*
G03X273868Y324641I-370J1456D01*
G01X273929Y324686D01*
X274242Y324798D01*
X274555Y324686D01*
X274616Y324641D01*
G03X276418I901J1201D01*
G01X276479Y324686D01*
X276792Y324798D01*
X277105Y324686D01*
X277166Y324641D01*
G03X279248Y324914I901J1201D01*
G01X279314Y324998D01*
X279719Y325211D01*
X279982Y325135D01*
X280034Y325106D01*
G03X280180Y325033I744J1305D01*
G03X280260Y325001I598J1378D01*
G03X280303Y324986I516J1411D01*
G03X280317Y324982I419J1442D01*
G03X280330Y324978I448J1433D01*
G02X280678Y324436I-148J-478D01*
G03X280802Y323616I1489J-194D01*
G02X280625Y322992I-455J-208D01*
G03X280065Y321189I836J-1248D01*
G03X282577Y320738I1396J555D01*
G03X282963Y321731I-1116J1005D01*
G03X282960Y321835I-1502J9D01*
G03X282826Y322370I-1499J-91D01*
G02X283003Y322994I455J208D01*
G03X283627Y323889I-836J1248D01*
G03X283631Y323906I-1460J352D01*
G03X283665Y324354I-1464J336D01*
G03X282613Y325676I-1498J-112D01*
G02X282265Y326218I148J478D01*
G03X282272Y326283I-1489J193D01*
G03X282276Y326337I-1495J138D01*
G02X283272Y327240I995J-97D01*
G01X283981D01*
X284889Y326332D01*
X285964D01*
G02X286964Y325337I0J-1000D01*
G01Y325328D01*
G03X288176Y323869I1502J15D01*
G03X289229Y324049I290J1474D01*
G03X289265Y326615I-763J1294D01*
G02X289047Y328126I531J848D01*
G01X291274Y330353D01*
X291384Y330463D01*
X293260Y332338D01*
X295346D01*
G02X295846Y331838I0J-500D01*
G01Y330036D01*
X295777Y329919D01*
G03X295716Y329802I1300J-752D01*
G02X295097Y329545I-452J214D01*
G03X293151Y327718I-501J-1416D01*
G03X295953Y327486I1445J411D01*
G02X296572Y327743I452J-214D01*
G03X298550Y328885I501J1416D01*
G02X299469Y329700I983J-183D01*
G03X300709Y330446I-59J1501D01*
G03X300432Y332302I-1299J755D01*
G02X300405Y333742I680J733D01*
G01X302599Y335936D01*
X308074D01*
X308215Y335816D01*
G03X310165I975J1143D01*
G01X310306Y335936D01*
X311230D01*
X313163Y334002D01*
X314050D01*
G02X314175Y333018I0J-500D01*
G03X314925I375J-1454D01*
G02X314550Y333502I125J484D01*
G01Y333710D01*
X314842Y334002D01*
X314921D01*
Y334003D01*
X315544D01*
X315778Y334237D01*
G02X317282Y334133I707J-708D01*
G03X319804Y335749I1199J905D01*
G02X319695Y336359I881J472D01*
G01X319715Y336506D01*
X319813Y336619D01*
G02X320518Y336667I377J-329D01*
G01X320712Y336498D01*
X320750Y336343D01*
G03X322085Y335199I1460J353D01*
G03X322690Y335273I124J1497D01*
G03X321895Y338165I-481J1423D01*
G02X320742Y338814I-209J978D01*
G03X320422Y339344I-1418J-495D01*
G02X320433Y340039I365J342D01*
G01X320966Y340572D01*
X321314Y340920D01*
X321456Y340952D01*
G03X322596Y342092I-326J1466D01*
G01X322628Y342234D01*
X329003Y348609D01*
X331775D01*
G02X332191Y348387I0J-500D01*
G03X334689I1249J834D01*
G02X335105Y348609I416J-278D01*
G01X344218D01*
X348170Y344657D01*
G03X349382Y343445I6161J4949D01*
G01X352610Y340217D01*
X359763D01*
X363680Y336300D01*
Y333152D01*
X363641Y333059D01*
G03Y331897I1385J-581D01*
G01X363680Y331804D01*
Y319488D01*
G02X362672Y318488I-1000J0D01*
G03X362238Y318428I-13J-1502D01*
G03X361711Y318150I423J-1441D01*
G02X360419Y318193I-621J784D01*
G03X357910Y317012I-1009J-1113D01*
G03X360359Y315916I1500J68D01*
G02X361651Y315873I621J-784D01*
G03X362318Y315523I1009J1113D01*
G03X363642Y315849I342J1463D01*
G02X364972Y315773I622J-783D01*
G01X372760Y307985D01*
Y305775D01*
X372705Y305667D01*
G03Y304293I1335J-687D01*
G01X372760Y304185D01*
Y302389D01*
X369860Y299489D01*
X367723D01*
X367279Y299933D01*
X367248Y299983D01*
G03X366759Y300472I-1278J-789D01*
G01X366709Y300503D01*
X366553Y300659D01*
G02X366479Y301270I354J353D01*
G01X366597Y301467D01*
G02X367074Y301707I429J-258D01*
G03X368198Y304342I146J1495D01*
G03X366455Y304494I-978J-1140D01*
G03X365762Y303564I764J-1293D01*
G02X364091Y303121I-964J265D01*
G01X363506Y303706D01*
X346855D01*
X342944Y307617D01*
Y318032D01*
X346930Y322018D01*
Y326412D01*
X345710Y327632D01*
X345374D01*
X345303Y327654D01*
G03X345098Y327705I-585J-1914D01*
G03X344720Y327740I-373J-1966D01*
G01X341910D01*
G03X339985Y326286I0J-2001D01*
G03X339983Y326281I1847J-742D01*
G01Y326280D01*
X339958Y326192D01*
X339946Y326126D01*
X339945Y326122D01*
G03X339942Y325376I1965J-381D01*
G01X339950Y325331D01*
Y322626D01*
X339459Y322135D01*
X323516D01*
G02X323048Y322458I0J500D01*
G03X321823Y323419I-1405J-530D01*
G03X321632Y323430I-182J-1491D01*
G03X321565Y323428I11J-1502D01*
G03X321549Y323427I86J-1499D01*
G03X320705Y323101I94J-1499D01*
G02X320081I-312J391D01*
G03X318205I-938J-1173D01*
G02X317581I-312J391D01*
G03X315705I-938J-1173D01*
G02X315081I-312J391D01*
G03X313205I-938J-1173D01*
G02X312581I-312J391D01*
G03X311999Y323387I-938J-1173D01*
G02X312023Y324364I118J486D01*
G03X311954Y327326I-283J1475D01*
G03X310775Y324688I-214J-1487D01*
G02X310748Y323134I-643J-766D01*
G03X310705Y323101I893J-1208D01*
G02X310081I-312J391D01*
G03X309237Y323427I-938J-1173D01*
G03X309221Y323428I-102J-1498D01*
G03X309154Y323430I-78J-1500D01*
G03X307715Y322396I-12J-1502D01*
G01Y322395D01*
X307668Y322253D01*
X307191Y321871D01*
X296983D01*
X296717Y322069D01*
X296670Y322229D01*
G03X296282Y322874I-1440J-427D01*
G03X294857Y323257I-1052J-1072D01*
G03X293728Y321821I373J-1455D01*
G03X293718Y321776I1472J-351D01*
G01X293688Y321629D01*
X293308Y321250D01*
X290747D01*
X288582Y319086D01*
X257222D01*
X255863Y320444D01*
X254213Y322094D01*
X252252D01*
X251130Y323216D01*
Y324942D01*
X249718Y326354D01*
Y338304D01*
X249791Y338424D01*
G03Y339990I-1282J783D01*
G01X249718Y340110D01*
Y341928D01*
X250677Y342887D01*
X250815Y342920D01*
G03X251927Y344032I-349J1461D01*
G01X251960Y344170D01*
X266731Y358941D01*
G02X268411Y358469I708J-707D01*
G03X268688Y357846I1475J283D01*
G02X268499Y356511I-826J-564D01*
G03X268166Y354583I957J-1158D01*
G02X268082Y353964I-429J-257D01*
G03X267663Y352499I1035J-1088D01*
G03X267667Y352484I1453J379D01*
G03X268917Y351387I1450J392D01*
G03X270407Y353646I200J1489D01*
G02X270491Y354265I429J257D01*
G03X270895Y354923I-1035J1088D01*
G03X270654Y356260I-1439J431D01*
G02X270843Y357595I826J564D01*
G03X271385Y358652I-957J1158D01*
G03X270175Y360227I-1499J101D01*
G02X269698Y361908I230J973D01*
G01X270250Y362460D01*
X270430Y362476D01*
G03X271789Y363835I-137J1496D01*
G01X271805Y364015D01*
X279373Y371583D01*
X279612Y371655D01*
X279735Y371631D01*
G03X280571Y371703I294J1473D01*
G01X280611Y371719D01*
X280801Y371757D01*
X280960Y371730D01*
X280995Y371720D01*
G03X282584Y374136I455J1431D01*
G01X282454Y374285D01*
X282468Y374678D01*
X282608Y374818D01*
X286397Y378607D01*
X297392D01*
X297526Y378506D01*
X297530Y378503D01*
G03X297552Y378486I929J1179D01*
G03X297652Y378420I877J1219D01*
G03X298431Y378202I779J1284D01*
G01X308904D01*
X309018Y378316D01*
X309161Y378460D01*
G02X309516Y378607I354J-353D01*
G01X311257D01*
Y381767D01*
G02X311439Y382153I500J0D01*
G03Y384471I-955J1159D01*
G02X311257Y384857I318J386D01*
G01Y388297D01*
X321091Y398131D01*
X321273Y398147D01*
G03X322082Y398470I-128J1496D01*
G02X322706I312J-391D01*
G03X324676Y398552I938J1173D01*
G02X325335Y398577I344J-363D01*
G03X327784Y399741I947J1166D01*
G03Y399755I-1502J7D01*
G03X327777Y399892I-1502J-8D01*
G03X325250Y400835I-1495J-149D01*
G02X324606Y400798I-344J363D01*
G01X324556Y400836D01*
X324530Y400862D01*
G02Y401570I353J354D01*
G01X331817Y408857D01*
Y409873D01*
X336485Y414541D01*
X337501D01*
X344551Y421591D01*
Y422719D01*
G02X346060Y423580I1000J0D01*
G03Y426120I802J1270D01*
G02X344551Y426981I-509J861D01*
G01Y436786D01*
X352155Y444390D01*
G02X353612Y444344I707J-707D01*
G03X356174Y445802I1138J981D01*
G03X355742Y446453I-1424J-476D01*
G02X355676Y447892I660J751D01*
G01X356866Y449082D01*
X357893Y450108D01*
X370058D01*
X371922Y448245D01*
X374061Y446105D01*
G02X374194Y445788I-367J-340D01*
G01Y442440D01*
X374618Y442015D01*
X374990Y441643D01*
Y431371D01*
X374905Y431245D01*
G03X374650Y430325I1245J-840D01*
G03X374707Y429988I1500J80D01*
G01X374745Y429856D01*
X374677Y429592D01*
X374580Y429495D01*
X369438Y424353D01*
Y417390D01*
X369204Y417111D01*
X369023Y417080D01*
G03X368457Y416857I256J-1480D01*
G03X368021Y416419I824J-1256D01*
G02X366668Y416134I-825J565D01*
G03X367109Y414055I-818J-1260D01*
G02X368462Y414340I825J-565D01*
G03X368717Y414208I815J1262D01*
G03X369024Y414120I565J1391D01*
G01X369204Y414089D01*
X369438Y413810D01*
Y400378D01*
X338231Y369171D01*
X337831D01*
X337759Y369193D01*
G03X336392Y368942I-443J-1435D01*
G02X335767Y368949I-308J394D01*
G03X335541Y369102I-951J-1162D01*
G03X335456Y369146I-732J-1311D01*
G03X335075Y369267I-641J-1358D01*
G03X334576Y369270I-258J-1480D01*
G03X334249Y369178I241J-1483D01*
G03X333340Y368069I566J-1391D01*
G01X333309Y367906D01*
X332821Y367458D01*
X323287D01*
G37*
G36*
G01X272223Y600135D02*
X256577D01*
X255995Y600717D01*
Y626854D01*
X257119Y627978D01*
X271241D01*
X272617D01*
X273674D01*
X274522Y627130D01*
Y600526D01*
X274131Y600135D01*
X272223D01*
G37*
G36*
G01X292322Y439396D02*
X290875Y440843D01*
X270298D01*
X269480Y441661D01*
Y447703D01*
X269669Y447892D01*
X324140D01*
X324808Y448560D01*
X325409D01*
X327265Y450415D01*
X331790D01*
X333610Y448595D01*
Y442986D01*
X330020Y439396D01*
X316715D01*
X316610Y439448D01*
G03X315270I-670J-1344D01*
G01X315165Y439396D01*
X292322D01*
G37*
G36*
G01X364271Y644745D02*
G02X364701Y644501I1J-500D01*
G03X367279I1289J771D01*
G02X367709Y644745I429J-256D01*
G01X370487D01*
X370856Y644376D01*
G02X370651Y642805I-708J-707D01*
G03X372545Y642488I756J-1298D01*
G01X372423Y642628D01*
Y642814D01*
G02X372923Y643314I500J0D01*
G01X373420D01*
X373530Y643204D01*
X383149D01*
X383259Y643314D01*
X392628D01*
X392894Y643117D01*
X392941Y642958D01*
G03X395819I1439J431D01*
G02X396298Y643314I479J-144D01*
G01X401468D01*
G02X402468Y642334I0J-1000D01*
G03X405472I1502J30D01*
G02X406472Y643314I1000J-20D01*
G01X418696D01*
X422980Y639030D01*
Y629557D01*
X420600Y627176D01*
X414582D01*
X413287Y625882D01*
X407927D01*
G02X406927Y626853I0J1000D01*
G03X403925I-1501J-44D01*
G02X402925Y625882I-1000J29D01*
G01X348648D01*
X347480Y624714D01*
Y619051D01*
X347540Y618991D01*
Y596532D01*
X338870Y587862D01*
X325932D01*
G02X325432Y588362I0J500D01*
G01Y589733D01*
G03X322430I-1501J0D01*
G01Y588362D01*
G02X321930Y587862I-500J0D01*
G01X308559D01*
X304910Y591511D01*
Y600387D01*
X306740Y602217D01*
Y604091D01*
G02X307240Y604591I500J0D01*
G01X318298D01*
X318590Y604303D01*
X318592Y604097D01*
G03X321596I1502J17D01*
G01X321598Y604303D01*
X321890Y604591D01*
X326767D01*
G02X327763Y603507I0J-1000D01*
G03X330594Y604072I1497J-126D01*
G02X330684Y604655I444J230D01*
G01X334100Y608071D01*
Y642119D01*
X334128Y642199D01*
G03Y643189I-1418J495D01*
G01X334100Y643269D01*
Y643925D01*
X334920Y644745D01*
X338919D01*
X339184Y644549D01*
X339232Y644390D01*
G03X342106I1437J437D01*
G02X342585Y644745I479J-145D01*
G01X345638D01*
G02X346450Y643161I0J-1000D01*
G03X347527Y640790I1220J-876D01*
G02X347729Y639859I-48J-498D01*
G03X347423Y639626I750J-1302D01*
G02X346264Y639446I-704J710D01*
G03X346637Y637041I-684J-1337D01*
G02X347796Y637221I704J-710D01*
G03X349187Y639883I684J1337D01*
G02X348863Y641373I471J883D01*
G03X348890Y643161I-1193J912D01*
G02X349702Y644745I812J584D01*
G01X359789D01*
G02X360232Y644477I0J-500D01*
G03X362892I1330J698D01*
G02X363335Y644745I443J-232D01*
G01X364271D01*
G37*
G36*
G01X307239Y605618D02*
X306660Y606197D01*
Y612620D01*
X304150Y615130D01*
Y619984D01*
X301872Y622262D01*
X298770D01*
X297660Y623372D01*
Y627517D01*
X298536Y628393D01*
X332584D01*
X333098Y627878D01*
Y609396D01*
X329320Y605618D01*
X307239D01*
G37*
G36*
G01X314055Y692161D02*
G03X313403Y689878I559J-1394D01*
G02X313354Y689229I-403J-296D01*
G01X311380Y687255D01*
Y677121D01*
X308917Y674658D01*
X305252D01*
X291200Y688709D01*
Y701250D01*
G02X292634Y702151I1000J0D01*
G03X294096Y702239I652J1353D01*
G02X295523Y701855I538J-842D01*
G03X296048Y703809I1335J689D01*
G02X294621Y704193I-538J842D01*
G03X292096Y704421I-1335J-689D01*
G02X291200Y704726I-396J305D01*
G01Y705027D01*
X293090Y706917D01*
X340522D01*
X341007Y706432D01*
X343453D01*
X343938Y706917D01*
X349845D01*
G02X350336Y706513I0J-500D01*
G03X353232Y706315I1474J287D01*
G02X353705Y706654I473J-161D01*
G01X362976D01*
X366448Y703182D01*
X366469Y702800D01*
X366349Y702651D01*
G03X366424Y700683I1171J-941D01*
G02X366413Y699988I-365J-342D01*
G01X366041Y699616D01*
X365712Y699569D01*
X365566Y699649D01*
G03X364219Y699698I-722J-1317D01*
G02X362997Y700016I-416J910D01*
G03X360284Y699154I-1211J-888D01*
G01X360281Y698949D01*
X359990Y698663D01*
X341399D01*
G02X340444Y699960I0J1000D01*
G03X337576I-1434J446D01*
G02X336621Y698663I-955J-297D01*
G01X334458D01*
G02X334024Y698915I0J500D01*
G03X333324Y699545I-1304J-745D01*
G02X332844Y700933I402J916D01*
G03X331405Y700144I-1324J709D01*
G02X331705Y699277I-38J-498D01*
G03X331416Y698915I1015J-1107D01*
G01X331349Y698798D01*
X331117Y698663D01*
X324898D01*
G02X323916Y699850I0J1000D01*
G03X323899Y700488I-1476J280D01*
G02X324570Y701681I971J239D01*
G03X322661Y702756I-450J1433D01*
G02X321990Y701563I-971J-239D01*
G03X321964Y701555I429J-1440D01*
G02X321382Y702295I-158J474D01*
G03X320033Y701593I-1272J798D01*
G02X320964Y700409I-52J-999D01*
G03X321505Y698954I1476J-279D01*
G02X321590Y697465I-622J-782D01*
G01X318616Y694491D01*
G02X317212Y694481I-707J707D01*
G03X314675Y693215I-1047J-1077D01*
G02X314055Y692161I-992J-126D01*
G37*
G36*
G01X320980Y343912D02*
G03X319915Y341535I150J-1494D01*
G01X320024Y341385D01*
X319996Y341018D01*
X318634Y339656D01*
X318576Y339623D01*
G03X318020Y339067I747J-1303D01*
G01X317987Y339009D01*
X316748Y337771D01*
Y337246D01*
X314506Y335004D01*
X313578D01*
X311390Y337192D01*
Y340376D01*
X318277Y347264D01*
X321380D01*
G02X321880Y346764I0J-500D01*
G01Y344907D01*
G02X320980Y343912I-1000J0D01*
G37*
G36*
G01X336941Y99243D02*
G03I-594J0D01*
G37*
G36*
G01X379031Y473851D02*
G02X378595Y474107I0J500D01*
G03X375973I-1311J-733D01*
G01X375906Y473988D01*
X375673Y473851D01*
X370263D01*
G02X369894Y474013I-1J500D01*
G03X367680I-1107J-1015D01*
G02X367311Y473851I-368J338D01*
G01X349356D01*
X346460Y476747D01*
Y479088D01*
X346746Y479375D01*
Y484027D01*
G02X347936Y485009I1000J0D01*
G03Y487959I284J1475D01*
G02X346746Y488941I-190J982D01*
G01Y499335D01*
G02X348196Y500229I1000J1D01*
G03Y502913I674J1342D01*
G02X346746Y503807I-450J893D01*
G01Y511605D01*
X347766Y512625D01*
G02X349444Y512158I707J-707D01*
G03X351792Y513730I1458J362D01*
G02X351707Y515271I593J806D01*
G03X352171Y516124I-1017J1106D01*
G01X352201Y516304D01*
X352481Y516540D01*
X352712D01*
X352745Y516536D01*
G03X353135I195J1489D01*
G01X353168Y516540D01*
X355147D01*
X355186Y516500D01*
X373535D01*
X377947Y512088D01*
G02X378014Y510748I-707J-707D01*
G03X380127Y508635I1163J-950D01*
G02X381467Y508568I633J-774D01*
G01X395788Y494246D01*
Y480130D01*
X389510Y473851D01*
X379031D01*
G37*
G36*
G01X374631Y94978D02*
G03I-594J0D01*
G37*
G36*
G01X391791Y104151D02*
G03I-594J0D01*
G37*
G36*
G01X389461Y97988D02*
G03I-594J0D01*
G37*
G36*
G01X410445Y595447D02*
G03X409709Y592684I77J-1500D01*
G02X409874Y591137I-542J-840D01*
G01X408905Y590168D01*
X405848D01*
X404460Y591555D01*
Y601119D01*
X405390Y602049D01*
X410398D01*
X410920Y601527D01*
Y595946D01*
G02X410445Y595447I-500J0D01*
G37*
G36*
G01X449192Y181827D02*
X462027D01*
X462070Y181820D01*
G03X462588I259J1479D01*
G01X462631Y181827D01*
X464531D01*
G02X465031Y181327I0J-500D01*
G01Y153327D01*
G02X464531Y152827I-500J0D01*
G01X444531D01*
G02X444031Y153327I0J500D01*
G01Y181327D01*
G02X444531Y181827I500J0D01*
G01X445423D01*
X449192D01*
G37*
G36*
G01X647370Y365580D02*
G02X648188Y367156I818J576D01*
G01X653860D01*
G02X654360Y366656I0J-500D01*
G01Y325879D01*
G02X653983Y325394I-500J0D01*
G03X653942Y325383I369J-1456D01*
G03X653434Y325127I410J-1445D01*
G02X652270I-582J813D01*
G03Y322749I-918J-1189D01*
G02X653434I582J-813D01*
G03X653942Y322493I918J1189D01*
G03X653983Y322482I410J1445D01*
G02X654360Y321997I-123J-485D01*
G01Y320892D01*
G02X653299Y319894I-1000J0D01*
G03X652244Y319587I-137J-1496D01*
G02X651080I-582J813D01*
G03Y317209I-918J-1189D01*
G02X652244I582J-813D01*
G03X652543Y317029I919J1188D01*
G03X652927Y316914I619J1369D01*
G02X653717Y315602I-156J-988D01*
G03X653828Y314308I1405J-531D01*
G03X654175Y313904I1295J761D01*
G01X654263Y313833D01*
X654360Y313629D01*
Y309243D01*
X654241Y309021D01*
X654135Y308952D01*
G03X653953Y308811I826J-1254D01*
G03X653572Y308266I1010J-1112D01*
G02X652922Y307992I-463J190D01*
G03X650938Y306122I-560J-1394D01*
G03X653291Y305418I1424J476D01*
G02X653778Y305492I309J-393D01*
G01X654039Y305392D01*
G02X654360Y304925I-179J-467D01*
G01Y304450D01*
G02X653919Y303954I-500J1D01*
G03Y300964I141J-1495D01*
G02X654360Y300468I-59J-497D01*
G01Y293890D01*
G02X653357Y292890I-1000J0D01*
G03X652007Y290719I-5J-1502D01*
G02X651924Y290121I-437J-244D01*
G01X637520Y275717D01*
Y202220D01*
G02X635944Y201401I-1000J-1D01*
G03X635207Y201718I-981J-1266D01*
G03X634923Y201737I-249J-1582D01*
G02X633934Y202473I-24J1000D01*
G03X631311Y203014I-1449J-396D01*
G03X632422Y200576I1174J-937D01*
G02X633360Y199610I-62J-998D01*
G01Y197042D01*
X632020Y195702D01*
Y195611D01*
X628970Y192561D01*
Y134995D01*
G02X628547Y134501I-500J0D01*
G03Y131523I191J-1489D01*
G02X628970Y131029I-77J-494D01*
G01Y122183D01*
G02X628573Y121694I-500J0D01*
G03Y118738I265J-1478D01*
G02X628970Y118249I-103J-489D01*
G01Y84477D01*
X626561Y82068D01*
X620458D01*
X618806Y83720D01*
G02X618672Y84187I353J354D01*
G01X618678Y84213D01*
G03X612614Y85518I-3021J702D01*
G02X612121Y85101I-493J83D01*
G01X594535D01*
G02X594046Y85493I-1J500D01*
G03X587956Y85518I-3047J-578D01*
G02X587463Y85101I-493J83D01*
G01X557701D01*
X557605Y85143D01*
G03X554757I-1424J-3254D01*
G01X554661Y85101D01*
X547701D01*
X547605Y85143D01*
G03X544757I-1424J-3254D01*
G01X544661Y85101D01*
X488776D01*
X485662Y88215D01*
Y105666D01*
X487110Y107114D01*
X519157D01*
X519223Y107096D01*
G03X520027I402J1447D01*
G01X520093Y107114D01*
X525920D01*
X526042Y107039D01*
G03X527628I793J1275D01*
G01X527750Y107114D01*
X532996D01*
X533043Y107161D01*
X533201Y107187D01*
G03X534242Y109444I-246J1482D01*
G01X534170Y109563D01*
Y110249D01*
X524977Y119442D01*
X500609D01*
X499150Y120901D01*
Y126673D01*
X499593Y127161D01*
X499754Y127194D01*
G03Y130138I-298J1472D01*
G01X499593Y130171D01*
X499150Y130659D01*
Y133948D01*
G02X500152Y134948I1000J0D01*
G03Y137950I63J1501D01*
G02X499150Y138950I-2J1000D01*
G01Y149488D01*
X489393Y159245D01*
X484920D01*
X484790Y159375D01*
Y163401D01*
X487142Y165753D01*
X495215D01*
X495311Y165849D01*
X495614Y165907D01*
X495761Y165843D01*
X495793Y165830D01*
G03X497736Y167824I567J1391D01*
G02X497840Y168378I458J201D01*
G01X505700Y176238D01*
Y182687D01*
X500510Y187877D01*
X495864D01*
X492049Y184062D01*
X484284D01*
X484008Y184289D01*
X483973Y184464D01*
G03X483498Y185292I-1473J-295D01*
G03X482264Y185652I-997J-1123D01*
G02X481695Y186051I-78J494D01*
G03X481041Y187024I-1475J-285D01*
G03X478783Y185329I-821J-1258D01*
G02X477819Y184062I-964J-267D01*
G01X476433D01*
G02X475933Y184562I0J500D01*
G02X476252Y185029I500J1D01*
G03X475626Y187946I-483J1422D01*
G03X474320Y186843I144J-1495D01*
G03X474528Y185606I1450J-392D01*
G02X473689Y184062I-839J-544D01*
G01X464351D01*
X464127Y184185D01*
X464058Y184294D01*
G03X461522I-1268J-805D01*
G01X461453Y184185D01*
X461229Y184062D01*
X460838D01*
X459604Y182828D01*
X449933D01*
G02X449602Y182974I23J500D01*
G01X445340Y187237D01*
Y223057D01*
X452376Y230093D01*
X478030D01*
X483880Y235943D01*
Y260674D01*
G02X484026Y261027I500J0D01*
G01X502779Y279779D01*
G02X504337Y279596I707J-707D01*
G03X509431Y284690I3152J1942D01*
G02X509248Y286248I524J851D01*
G01X515530Y292530D01*
X530904D01*
X605530Y367156D01*
X644154D01*
G02X644972Y365580I0J-1000D01*
G03X647370I1199J-904D01*
G37*
G36*
G01X516629Y659701D02*
G02X516697Y660886I837J546D01*
G03X514283Y661024I-1156J959D01*
G02X514215Y659839I-837J-546D01*
G03X514254Y657876I1156J-959D01*
G01X514255Y657875D01*
X514312Y657811D01*
X514389Y657626D01*
G02X514281Y657081I-462J-192D01*
G01X511120Y653920D01*
X507484D01*
X507192Y654212D01*
Y654420D01*
G03X504188I-1502J-1D01*
G01Y654212D01*
X503896Y653920D01*
X502639D01*
G02X502286Y654066I0J500D01*
G01X499077Y657276D01*
X482991D01*
X482478Y657788D01*
X481324D01*
G02X480357Y659043I0J1000D01*
G03X477571Y658735I-1452J383D01*
G02X476683Y657276I-888J-459D01*
G01X473080D01*
G02X472580Y657776I0J500D01*
G01Y670985D01*
X477557Y675962D01*
G02X478102Y676070I353J-354D01*
G01X478287Y675993D01*
X478368Y675921D01*
X478405Y675891D01*
G03X480704Y676396I949J1163D01*
G02X481153Y676677I450J-219D01*
G01X488656D01*
G02X489656Y675648I0J-1000D01*
G03X492493Y676289I1501J-45D01*
G02X492585Y676872I445J229D01*
G01X492824Y677110D01*
X495214D01*
X495350Y677003D01*
G03X497204I927J1182D01*
G01X497340Y677110D01*
X498310D01*
Y680060D01*
X499111Y680862D01*
G02X500506Y680880I707J-707D01*
G03X502630Y683004I1034J1090D01*
G02X502648Y684399I725J688D01*
G01X503346Y685097D01*
Y685956D01*
X505812Y688422D01*
X507632D01*
X509141Y689930D01*
X513598D01*
X514202Y689326D01*
X515422D01*
G02X516408Y688156I1J-1000D01*
G03X516404Y688132I1479J-259D01*
G02X515419Y687285I-988J153D01*
G03X516289Y684554I6J-1502D01*
G02X517696Y684290I575J-818D01*
G03X519758Y686386I1251J832D01*
G02X519335Y687497I540J842D01*
G03X519256Y688521I-1447J403D01*
G02X520167Y689934I911J413D01*
G01X529817D01*
X530092Y689710D01*
X530128Y689535D01*
G03X533003Y689303I1471J303D01*
G02X533470Y689625I467J-178D01*
G01X552184D01*
X554200Y691641D01*
G02X554733Y691754I353J-354D01*
G03X555082Y691666I539J1402D01*
G01X555254Y691644D01*
X555399Y691496D01*
G02X555405Y690803I-357J-350D01*
G01X555275Y690665D01*
X555109Y690637D01*
G03X554433Y687972I248J-1481D01*
G02X554404Y686373I-615J-789D01*
G03X554367Y683966I880J-1217D01*
G02X554347Y682368I-611J-791D01*
G03X554355Y679939I888J-1212D01*
G02X554384Y678340I-586J-810D01*
G03X554406Y675955I924J-1184D01*
G02Y674357I-601J-799D01*
G03X556210I902J-1201D01*
G02Y675955I601J799D01*
G03X556188Y678373I-902J1201D01*
G02X556159Y679972I586J810D01*
G03X556152Y682346I-924J1184D01*
G02X556172Y683944I611J791D01*
G03X556208Y686340I-888J1212D01*
G02X556237Y687939I615J789D01*
G03X556233Y690376I-880J1217D01*
G02X556199Y691975I583J812D01*
G03X556673Y693695I-928J1181D01*
G02X556786Y694227I467J179D01*
G01X561440Y698881D01*
X563707D01*
X563913Y698780D01*
X563988Y698686D01*
X564001Y698669D01*
G03X566351Y698689I1167J945D01*
G01X566422Y698780D01*
X566630Y698881D01*
X582969D01*
G02X583941Y697644I0J-1000D01*
G03X584940Y695859I1459J-355D01*
G02X585577Y694577I-307J-952D01*
G03X587455Y695510I1418J-497D01*
G02X586818Y696792I307J952D01*
G03X586859Y697644I-1418J495D01*
G02X587831Y698881I972J237D01*
G01X602226D01*
X606362Y703017D01*
G02X606755Y703162I354J-353D01*
G01X606792Y703159D01*
X606808Y703157D01*
X606810D01*
G03X608453Y704195I210J1487D01*
G01X608502Y704351D01*
X608766Y704545D01*
X615428D01*
G02X616428Y703535I0J-1000D01*
G03X619432I1502J-15D01*
G02X620432Y704545I1000J10D01*
G01X645174D01*
X645528Y704192D01*
X649433Y708097D01*
X650190D01*
X654086Y711993D01*
G02X654794Y711992I354J-354D01*
G01X654948Y711838D01*
X655761D01*
X655880Y711767D01*
G03X657686Y714145I771J1289D01*
G02X657669Y715576I690J724D01*
G01X681160Y739067D01*
Y767643D01*
X673360Y775443D01*
Y778110D01*
G02X673520Y778477I500J0D01*
G03X673817Y780302I-1020J1103D01*
G02X674132Y781611I876J482D01*
G03X673775Y784277I-842J1244D01*
G01X673716Y784297D01*
X673360Y784774D01*
Y790430D01*
X676500Y793570D01*
X684050D01*
G02X684550Y793070I0J-500D01*
G01Y787487D01*
X686440Y785597D01*
X700467D01*
X719748Y766316D01*
X719819Y766062D01*
X719787Y765936D01*
G03X720042Y764677I1458J-360D01*
G02X720095Y764168I-401J-299D01*
G01X720018Y764003D01*
X719995Y763979D01*
G03X719901Y763873I1106J-1075D01*
G01X719803Y763751D01*
X719301Y763984D01*
X719236Y764052D01*
G03X718506Y764474I-1086J-1037D01*
G02X717745Y765498I238J971D01*
G03X715889Y764117I-1500J78D01*
G02X716650Y763093I-238J-971D01*
G03X718989Y761769I1500J-78D01*
G02X719981Y761842I560J-829D01*
G03X721228Y761366I1119J1061D01*
G02X721950Y760406I-278J-961D01*
G01Y690640D01*
G03Y688160I-850J-1240D01*
G01Y672855D01*
X699790Y650695D01*
X699730D01*
X694474Y645439D01*
X686950D01*
X673205Y631694D01*
Y624170D01*
X673200Y624165D01*
Y611509D01*
X671970Y610279D01*
X665512D01*
X651755Y624036D01*
X645287D01*
G02X644291Y624949I0J1000D01*
G03X644285Y625010I-1498J-117D01*
G01X644283Y625024D01*
X644281Y625058D01*
G02X644416Y625435I499J34D01*
G01X644711Y625747D01*
X644878Y625774D01*
G03X643134Y627241I-242J1483D01*
G02X642398Y626267I-1000J-10D01*
G03X641299Y624949I397J-1449D01*
G02X640303Y624036I-996J87D01*
G01X630336D01*
G02X629397Y625379I0J1000D01*
G03X629480Y626051I-1411J515D01*
G02X630197Y627116I995J104D01*
G03X628287Y628403I-416J1443D01*
G02X627570Y627338I-995J-104D01*
G03X626575Y625379I416J-1443D01*
G02X625636Y624036I-939J-343D01*
G01X618142D01*
G02X617162Y625236I0J1000D01*
G03X614363Y624832I-1472J300D01*
G01X614390Y624782D01*
X614421Y624665D01*
G02X613938Y624036I-483J-129D01*
G01X613643D01*
X590048Y647631D01*
G02X590034Y649030I707J707D01*
G03X587910Y651154I-1084J1040D01*
G02X586511Y651168I-692J721D01*
G01X585434Y652245D01*
X585432Y652450D01*
G03X583941Y653941I-1502J-11D01*
G01X583736Y653943D01*
X581330Y656349D01*
X578517D01*
X577549Y657317D01*
G02X577749Y658886I707J707D01*
G03X578150Y661129I-762J1294D01*
G01X578120Y661166D01*
X578048Y661247D01*
X577971Y661432D01*
G02X578079Y661977I462J192D01*
G01X578433Y662331D01*
G02X579738Y662426I707J-707D01*
G03X582051Y664136I899J1203D01*
G02X582992Y665474I941J338D01*
G01X583261D01*
G02X583761Y664974I0J-500D01*
G01Y664816D01*
X583671Y664687D01*
G03X586354Y664216I1232J-859D01*
G02X587320Y665474I966J258D01*
G01X595191D01*
G02X596034Y663936I0J-1000D01*
G03X597882Y664513I1266J-808D01*
G01X597717Y664582D01*
X597550Y664898D01*
X597586Y665074D01*
G02X598076Y665474I490J-100D01*
G01X599107D01*
G02X600099Y664603I0J-1000D01*
G03X602790Y665698I1489J195D01*
G02X602837Y666351I400J299D01*
G01X603688Y667202D01*
Y670504D01*
X603724Y670594D01*
G03X600848Y670923I-1392J562D01*
G02X600210Y669832I-988J-154D01*
G03X599977Y669720I532J-1404D01*
G01X599976D01*
X599858Y669652D01*
X580834D01*
X580567Y669854D01*
X580521Y670015D01*
G03X577625Y669990I-1445J-412D01*
G02X576603Y669250I-966J258D01*
G03X575501Y666646I-83J-1500D01*
G02X575530Y665204I-678J-735D01*
G01X569982Y659656D01*
G02X568346Y659994I-707J707D01*
G03X566071Y660657I-1396J-555D01*
G02X564832Y660711I-585J811D01*
G03X564729Y658357I-982J-1136D01*
G02X565968Y658303I585J-811D01*
G03X567085Y657943I983J1136D01*
G01X567132Y657947D01*
X567241Y657905D01*
G02X567413Y657086I-182J-466D01*
G01X566792Y656466D01*
X562617D01*
X560888Y654738D01*
Y652706D01*
G02X560388Y652206I-500J0D01*
G01X559877D01*
X559816Y652222D01*
G03X559064I-376J-1455D01*
G01X559003Y652206D01*
X558028D01*
X546626Y640804D01*
X516310D01*
X515823Y641240D01*
X515789Y641399D01*
G03X513188Y640098I-1469J-314D01*
G01X513189Y640097D01*
X513244Y640033D01*
X513318Y639853D01*
G02X513208Y639310I-463J-189D01*
G01X512122Y638224D01*
X486120D01*
X481777Y642567D01*
X481740Y642682D01*
G03X480768Y643654I-1430J-458D01*
G01X480653Y643691D01*
X472580Y651764D01*
Y654322D01*
G02X473080Y654822I500J0D01*
G01X479488D01*
X479766Y654608D01*
X479781Y654535D01*
G03X482705Y654451I1472J302D01*
G01X482749Y654615D01*
X483018Y654822D01*
X489457D01*
G02X490445Y653975I0J-1000D01*
G03X493415I1485J228D01*
G02X494403Y654822I988J-153D01*
G01X496299D01*
G02X497245Y653499I0J-1000D01*
G03X499664Y651889I1421J-487D01*
G02X501035Y651849I664J-747D01*
G01X501416Y651468D01*
X501944D01*
G02X502884Y650126I0J-1000D01*
G03X505706I1411J-514D01*
G02X506646Y651468I940J342D01*
G01X512137D01*
X515000Y654330D01*
G02X516355Y654385I707J-707D01*
G03X518830Y655528I973J1144D01*
G02X519330Y656028I500J0D01*
G01X523195D01*
G02X524193Y654961I0J-1000D01*
G03X527191I1499J-99D01*
G02X528189Y656028I998J67D01*
G01X534292D01*
X535069Y655251D01*
X535103Y655120D01*
G03X536935Y656952I1454J378D01*
G01X536804Y656986D01*
X535309Y658480D01*
X517370D01*
G02X516871Y658955I0J500D01*
G03X516629Y659701I-1500J-74D01*
G37*
G36*
G01X498768Y420120D02*
Y432011D01*
G02X499268Y432511I500J0D01*
G01X508757D01*
X508857Y432465D01*
G03X510115I629J1364D01*
G01X510215Y432511D01*
X518000D01*
G02X518500Y432011I0J-500D01*
G01Y420120D01*
G02X518000Y419620I-500J0D01*
G01X499268D01*
G02X498768Y420120I0J500D01*
G37*
G36*
G01X507490Y476038D02*
X509886Y478434D01*
X537925D01*
X539200Y477159D01*
Y448729D01*
X537400Y446929D01*
X535272D01*
X535198Y446953D01*
G03X534278I-460J-1430D01*
G01X534204Y446929D01*
X509003D01*
X507490Y448442D01*
Y476038D01*
G37*
G36*
G01X583901Y564610D02*
G03Y561786I512J-1412D01*
G02X584230Y561316I-171J-470D01*
G01Y554708D01*
G02X583353Y553716I-1000J0D01*
G03Y550734I185J-1491D01*
G02X584230Y549742I-123J-992D01*
G01Y549496D01*
G02X584050Y549112I-500J0D01*
G03Y546806I963J-1153D01*
G02X584230Y546422I-320J-384D01*
G01Y544074D01*
X576135Y535979D01*
X564809D01*
G02X563809Y536945I-1J1000D01*
G03X562787Y538319I-1501J-50D01*
G02X562199Y539690I318J948D01*
G03X562315Y540051I-1361J636D01*
G02X562902Y540451I492J-91D01*
G03X563396Y543413I286J1474D01*
G02X562547Y544241I138J990D01*
G03X559981Y542958I-1482J-243D01*
G02X559890Y541490I-722J-692D01*
G03X560359Y538901I948J-1165D01*
G02X560947Y537530I-318J-948D01*
G03X560807Y536945I1361J-635D01*
G02X559807Y535979I-999J34D01*
G01X549160D01*
X546493Y538646D01*
X546437Y538955D01*
X546503Y539098D01*
G03X544511Y541090I-1365J627D01*
G01X544368Y541024D01*
X544059Y541080D01*
X543590Y541549D01*
Y545587D01*
G02X544919Y546532I1000J0D01*
G03Y549368I494J1418D01*
G02X543590Y550313I-329J945D01*
G01Y552835D01*
X517948Y578477D01*
X515291D01*
X515255Y578514D01*
X497332D01*
X496840Y579005D01*
Y591780D01*
X500064Y595004D01*
X560620D01*
X573650Y581974D01*
G02X573660Y580571I-708J-707D01*
G03X573840Y578321I1078J-1046D01*
G02X573895Y576762I-598J-802D01*
G03X574168Y574300I981J-1137D01*
G02X574432Y572742I-472J-881D01*
G03X576246Y573050I1106J-1017D01*
G02X575982Y574608I472J881D01*
G03X575774Y576829I-1106J1017D01*
G02X575719Y578388I598J802D01*
G03X575784Y578447I-976J1141D01*
G02X577187Y578437I696J-718D01*
G01X581498Y574126D01*
G02X581283Y572549I-708J-707D01*
G03X582748Y569926I740J-1307D01*
G02X584230Y569050I482J-876D01*
G01Y565080D01*
G02X583901Y564610I-500J0D01*
G37*
G36*
G01X545910Y623191D02*
Y633541D01*
G02X546410Y634041I500J0D01*
G01X559803D01*
X560054Y633790D01*
Y622797D01*
X559947Y622690D01*
X546411D01*
X545910Y623191D01*
G37*
G36*
G01X602693Y609094D02*
G03X602611Y609113I-380J-1453D01*
G02X602210Y609603I99J490D01*
G01Y616636D01*
X606020Y620446D01*
X652730D01*
X661670Y611506D01*
X662869D01*
X665097Y609278D01*
X672385D01*
X674202Y611094D01*
Y614418D01*
X675330Y615546D01*
Y629866D01*
X685200Y639736D01*
X723420D01*
X760640Y602516D01*
Y559826D01*
X759190Y558376D01*
X743052D01*
X737504Y563924D01*
X712480D01*
G02X712079Y564126I0J500D01*
G03X709667I-1206J-896D01*
G02X709266Y563924I-401J298D01*
G01X693431D01*
G02X692956Y564265I-1J500D01*
G03X692434Y564990I-1425J-475D01*
G02Y566588I601J799D01*
G03Y568990I-902J1201D01*
G02Y570588I601J799D01*
G03Y572990I-902J1201D01*
G02Y574588I601J799D01*
G03Y576990I-902J1201D01*
G02Y578588I601J799D01*
G03Y580990I-902J1201D01*
G02Y582588I601J799D01*
G03Y584990I-902J1201D01*
G02Y586588I601J799D01*
G03X690630I-902J1201D01*
G02Y584990I-601J-799D01*
G03Y582588I902J-1201D01*
G02Y580990I-601J-799D01*
G03Y578588I902J-1201D01*
G02Y576990I-601J-799D01*
G03Y574588I902J-1201D01*
G02Y572990I-601J-799D01*
G03Y570588I902J-1201D01*
G02Y568990I-601J-799D01*
G03Y566588I902J-1201D01*
G02Y564990I-601J-799D01*
G03X690108Y564265I903J-1200D01*
G02X689633Y563924I-474J159D01*
G01X685424D01*
X674882Y574466D01*
X649248D01*
G02X648298Y575777I0J1000D01*
G03X645442I-1428J466D01*
G02X644492Y574466I-950J-311D01*
G01X641732D01*
G02X640909Y576034I0J1000D01*
G03X638437I-1236J854D01*
G02X637614Y574466I-823J-568D01*
G01X635854D01*
X603699Y606621D01*
X603640Y606919D01*
X603699Y607060D01*
G03X603765Y607251I-1384J585D01*
G02X604983Y607960I966J-259D01*
G03X603911Y609803I379J1454D01*
G02X602693Y609094I-966J259D01*
G37*
G36*
G01X625340Y563591D02*
Y554731D01*
X650850D01*
Y563591D01*
X625340D01*
G37*
G36*
G01X667207Y364359D02*
G02X667636Y364116I0J-500D01*
G03X670214I1289J771D01*
G01X670282Y364229D01*
X670510Y364359D01*
X677630D01*
G02X678130Y363859I0J-500D01*
G01Y355029D01*
G02X677630Y354529I-500J0D01*
G01X655950D01*
G02X655450Y355029I0J500D01*
G01Y363859D01*
G02X655950Y364359I500J0D01*
G01X667207D01*
G37*
G36*
G01X745010Y315263D02*
X746280Y316533D01*
X757594D01*
X757930Y316197D01*
Y309583D01*
X757375Y309028D01*
X745610D01*
X745010Y309628D01*
Y315263D01*
G37*
%LPC*%
G75*
G36*
G01X172006Y447214D02*
G03X171382I-312J-391D01*
G02Y449560I-938J1173D01*
G03X172006I312J391D01*
G02Y447214I938J-1173D01*
G37*
G36*
G01X230781Y440545D02*
G03X230785Y441230I-363J345D01*
G02X232974Y441218I1100J1022D01*
G03X232970Y440533I363J-345D01*
G02X230781Y440545I-1100J-1022D01*
G37*
G36*
G01X139610Y437492D02*
G03Y436868I391J-312D01*
G02X137264I-1173J-938D01*
G03Y437492I-391J312D01*
G02Y439368I1173J938D01*
G03Y439992I-391J312D01*
G02X139610I1173J938D01*
G03Y439368I391J-312D01*
G02Y437492I-1173J-938D01*
G37*
G36*
G01X87252Y436570D02*
G03Y435370I800J-600D01*
G02X84848I-1202J-900D01*
G03Y436570I-800J600D01*
G02X87252I1202J900D01*
G37*
G36*
G01X230108Y435660D02*
G03Y434460I800J-600D01*
G02X227704I-1202J-900D01*
G03Y435660I-800J600D01*
G02X230108I1202J900D01*
G37*
G36*
G01X102731Y435033D02*
G03Y434338I360J-347D01*
G02X100569I-1081J-1042D01*
G03Y435033I-360J347D01*
G02X102731I1081J1042D01*
G37*
G36*
G01X245338Y434635D02*
G03Y433985I380J-325D01*
G02X243054I-1142J-975D01*
G03Y434635I-380J325D01*
G02X245338I1142J975D01*
G37*
G36*
G01X111403Y362297D02*
G03Y361673I391J-312D01*
G02X109057I-1173J-938D01*
G03Y362297I-391J312D01*
G02X111403I1173J938D01*
G37*
G36*
G01X25250Y13790D02*
G02X22979Y14090I-1263J-813D01*
G03X23148Y15373I-672J741D01*
G02X25419Y15073I1263J813D01*
G03X25250Y13790I672J-741D01*
G37*
G36*
G01X223491Y44602D02*
G02Y46406I-1201J902D01*
G03X225089I799J601D01*
G02X227491I1201J-902D01*
G03X229089I799J601D01*
G02Y44602I1201J-902D01*
G03X227491I-799J-601D01*
G02X225089I-1201J902D01*
G03X223491I-799J-601D01*
G37*
G36*
G01X243491D02*
G02Y46406I-1201J902D01*
G03X245089I799J601D01*
G02X247491I1201J-902D01*
G03X249089I799J601D01*
G02Y44602I1201J-902D01*
G03X247491I-799J-601D01*
G02X245089I-1201J902D01*
G03X243491I-799J-601D01*
G37*
G36*
G01X173162Y47928D02*
G02X170759Y48769I-938J1173D01*
G03X169530Y49515I-975J-221D01*
G02X170115Y52119I-381J1453D01*
G03X170883Y52277I322J383D01*
G02X171051Y52539I1341J-675D01*
G03Y53163I-391J312D01*
G02X173162Y55274I1173J938D01*
G03X173786I312J391D01*
G02X175662I938J-1173D01*
G03X176286I312J391D01*
G02X178397Y53163I938J-1173D01*
G03Y52539I391J-312D01*
G02Y50663I-1173J-938D01*
G03Y50039I391J-312D01*
G02X176286Y47928I-1173J-938D01*
G03X175662I-312J-391D01*
G02X173786I-938J1173D01*
G03X173162I-312J-391D01*
G37*
G36*
G01X46796Y49598D02*
G02X46750Y51417I-1218J879D01*
G03X48341Y51457I780J625D01*
G02X48387Y49638I1218J-879D01*
G03X46796Y49598I-780J-625D01*
G37*
G36*
G01X248103Y51770D02*
G02X248101Y49957I1197J-908D01*
G03X246507Y49959I-798J-603D01*
G02X244083Y50000I-1197J908D01*
G03X242484Y50047I-817J-577D01*
G02X240109Y50081I-1174J936D01*
G03X238511I-799J-601D01*
G02Y51885I-1201J902D01*
G03X240109I799J601D01*
G02X242537Y51850I1201J-902D01*
G03X244136Y51803I817J577D01*
G02X246509Y51772I1174J-936D01*
G03X248103Y51770I798J603D01*
G37*
G36*
G01X232109Y51973D02*
G02X232082Y50152I1181J-928D01*
G03X230491Y50175I-804J-594D01*
G02X228109Y50201I-1181J928D01*
G03X226511I-799J-601D01*
G02X224109I-1201J902D01*
G03X222511I-799J-601D01*
G02Y52005I-1201J902D01*
G03X224109I799J601D01*
G02X226511I1201J-902D01*
G03X228109I799J601D01*
G02X230518Y51996I1201J-902D01*
G03X232109Y51973I804J594D01*
G37*
G36*
G01X49782Y59586D02*
G02X49778Y57781I1199J-905D01*
G03X48180Y57785I-801J-599D01*
G02X48184Y59590I-1199J905D01*
G03X49782Y59586I801J599D01*
G37*
G36*
G01X148006Y60975D02*
G02X147939Y59132I1151J-965D01*
G03X146361Y59189I-811J-585D01*
G02X146428Y61032I-1151J965D01*
G03X148006Y60975I811J585D01*
G37*
G36*
G01X56482Y74815D02*
G02X55834Y72526I558J-1394D01*
G03X54659Y72858I-803J-596D01*
G02X55307Y75147I-558J1394D01*
G03X56482Y74815I803J596D01*
G37*
G36*
G01X105024Y168673D02*
G02X104855Y166761I1066J-1058D01*
G03X103323Y166897I-823J-569D01*
G02X103492Y168809I-1066J1058D01*
G03X105024Y168673I823J569D01*
G37*
G36*
G01X98792Y368639D02*
G02X98743Y366836I1176J-934D01*
G03X97144Y366880I-816J-578D01*
G02X97193Y368683I-1176J934D01*
G03X98792Y368639I816J578D01*
G37*
G36*
G01X91358Y419624D02*
G02X88994Y419465I-1120J-1001D01*
G03X88911Y420692I-828J560D01*
G02X91275Y420851I1120J1001D01*
G03X91358Y419624I828J-560D01*
G37*
G36*
G01X99637Y419780D02*
G02X97267Y419734I-1167J-946D01*
G03X97243Y420962I-801J599D01*
G02X99613Y421008I1167J946D01*
G03X99637Y419780I801J-599D01*
G37*
G36*
G01X87091Y426194D02*
G02X85009I-1041J-1082D01*
G03Y427636I-694J721D01*
G02X87091I1041J1082D01*
G03Y426194I694J-721D01*
G37*
G36*
G01X102806Y426510D02*
G02X100494I-1156J-958D01*
G03Y427787I-770J638D01*
G02X102806I1156J958D01*
G03Y426510I770J-638D01*
G37*
G36*
G01X148857Y443015D02*
G02X146636Y442854I-1038J-1086D01*
G03X146539Y444193I-788J616D01*
G02X146403Y446217I1037J1086D01*
G03Y446841I-391J312D01*
G02Y448717I1173J938D01*
G03Y449341I-391J312D01*
G02X148749I1173J938D01*
G03Y448717I391J-312D01*
G02Y446841I-1173J-938D01*
G03Y446217I391J-312D01*
G02X148760Y444354I-1173J-938D01*
G03X148857Y443015I788J-616D01*
G37*
G36*
G01X222870Y441190D02*
G02X220763Y441272I-1012J1110D01*
G03X219414Y441372I-729J-685D01*
G02X219578Y443578I-931J1178D01*
G03X220927Y443478I729J685D01*
G02X222747Y443511I932J-1178D01*
G03X224012Y443577I592J806D01*
G02X225992Y443616I1012J-1110D01*
G03X226689Y443668I322J382D01*
G02X226848Y441526I1127J-993D01*
G03X226151Y441474I-322J-382D01*
G02X224135Y441256I-1127J993D01*
G03X222870Y441190I-592J-806D01*
G37*
G36*
G01X102795Y444010D02*
G02X100469Y443966I-1145J-972D01*
G03X100445Y445231I-786J618D01*
G02X102771Y445275I1145J972D01*
G03X102795Y444010I786J-618D01*
G37*
G36*
G01X153076Y51650D02*
X152789Y51594D01*
X152502Y51650D01*
G02X153076I287J1474D01*
G37*
G36*
G01X137130Y726511D02*
G03X136204Y725771I40J-999D01*
G02X134693Y727662I-1451J390D01*
G03X135619Y728402I-40J999D01*
G02X137130Y726511I1451J-390D01*
G37*
G36*
G01X108424Y712215D02*
G02X102287Y684698I-9996J-12213D01*
G02X88461Y712239I-3861J15302D01*
G03X89142Y713711I-1253J1473D01*
G01Y719686D01*
G02X107714I9286J0D01*
G01Y713711D01*
G03X108424Y712215I1934J2D01*
G37*
G36*
G01X62447Y619867D02*
G03X62369Y620576I-387J316D01*
G02X61813Y621540I931J1179D01*
G03X60976Y622386I-990J-142D01*
G02X62692Y624085I229J1484D01*
G03X63529Y623239I990J142D01*
G02X64463Y620805I-229J-1484D01*
G03X64541Y620096I387J-316D01*
G02X62447Y619867I-931J-1179D01*
G37*
G36*
G01X121195Y740135D02*
G02X119217Y739867I-838J-1246D01*
G03X119203Y741185I-759J651D01*
G02X121338Y743293I1119J1002D01*
G03X122615Y743231I676J737D01*
G02X122502Y740924I903J-1200D01*
G03X121225Y740986I-676J-737D01*
G02X121187Y740959I-889J1211D01*
G03X121195Y740135I287J-409D01*
G37*
G36*
G01X133766Y732527D02*
G02X132369Y734484I-1432J455D01*
G03X133345Y735181I23J999D01*
G02X133875Y735927I1431J-456D01*
G03Y737525I-601J799D01*
G02X133735Y739807I902J1201D01*
G03X133712Y741269I-694J720D01*
G02X135762Y741301I1008J1113D01*
G03X135785Y739839I694J-720D01*
G02X135679Y737525I-1008J-1113D01*
G03Y735927I601J-799D01*
G02X134742Y733224I-902J-1201D01*
G03X133766Y732527I-23J-999D01*
G37*
G36*
G01X174150Y729673D02*
G02X173798Y727445I804J-1269D01*
G03X172493Y727651I-770J-638D01*
G02X172845Y729879I-804J1269D01*
G03X174150Y729673I770J638D01*
G37*
G36*
G01X179180Y699177D02*
G02X177376I-902J-1201D01*
G03Y700775I-601J799D01*
G02Y703177I902J1201D01*
G03Y704775I-601J799D01*
G02Y707177I902J1201D01*
G03Y708775I-601J799D01*
G02X179180I902J1201D01*
G03Y707177I601J-799D01*
G02Y704775I-902J-1201D01*
G03Y703177I601J-799D01*
G02Y700775I-902J-1201D01*
G03Y699177I601J-799D01*
G37*
G36*
G01X60693Y642159D02*
G02X59750Y644364I-1303J747D01*
G03X60857Y644838I239J971D01*
G02X61589Y645480I1303J-747D01*
G03X62185Y646626I-379J925D01*
G02X64221Y645568I1465J331D01*
G03X63625Y644422I379J-925D01*
G02X61800Y642633I-1465J-331D01*
G03X60693Y642159I-239J-971D01*
G37*
G36*
G01X62651Y628464D02*
G02X59728Y629145I-1446J405D01*
G03X59059Y630278I-983J184D01*
G02X58994Y630301I468J1427D01*
G03X57679Y629652I-356J-935D01*
G02X56776Y631484I-1439J429D01*
G03X58091Y632133I356J935D01*
G02X60931Y631162I1440J-428D01*
G03X61713Y630594I466J-180D01*
G03X62044Y631099I-632J775D01*
G02X63564Y629193I1446J-406D01*
G03X62651Y628464I50J-999D01*
G37*
G36*
G01X50711Y620870D02*
G02X49595Y619038I340J-1463D01*
G03X48400Y619766I-969J-246D01*
G02X47219Y622474I-340J1463D01*
G03X47411Y623962I-559J829D01*
G02X48101Y626389I1129J991D01*
G03X48792Y627524I-293J956D01*
G02X50709Y626357I1478J269D01*
G03X50018Y625222I293J-956D01*
G02X49381Y623708I-1478J-269D01*
G03X49189Y622220I559J-829D01*
G02X49516Y621598I-1129J-991D01*
G03X50711Y620870I969J246D01*
G37*
G36*
G01X16840Y612110D02*
G02X14559Y611748I-990J-1130D01*
G03X14359Y613012I-859J512D01*
G02X16640Y613374I990J1130D01*
G03X16840Y612110I859J-512D01*
G37*
G36*
G01X40399Y602051D02*
G02X38335Y602045I-1029J-1095D01*
G03X38331Y603498I-689J725D01*
G02X40395Y603504I1029J1095D01*
G03X40399Y602051I689J-725D01*
G37*
G36*
G01X14844Y591249D02*
G02X14283Y593227I-1334J690D01*
G03X15686Y593624I515J857D01*
G02X16247Y591646I1334J-690D01*
G03X14844Y591249I-515J-857D01*
G37*
G36*
G01X63348Y464361D02*
G03X62203Y464211I-466J-884D01*
G02X61885Y466642I-1020J1103D01*
G03X63030Y466792I466J884D01*
G02X64800Y466991I1020J-1103D01*
G03X65473Y467159I249J433D01*
G02X65997Y465061I1274J-796D01*
G03X65324Y464893I-249J-433D01*
G02X63348Y464361I-1274J796D01*
G37*
G36*
G01X125062Y458646D02*
G02X123024Y458640I-1022J1100D01*
G03X121841Y458765I-676J-737D01*
G02X122096Y461166I-761J1295D01*
G03X123279Y461041I676J737D01*
G02X124831Y461023I761J-1295D01*
G03X126038Y461140I527J850D01*
G02X126269Y458763I1022J-1100D01*
G03X125062Y458646I-527J-850D01*
G37*
G36*
G01X181185Y632556D02*
G03X181235Y633744I-778J628D01*
G02X183648Y633641I1245J841D01*
G03X183598Y632453I778J-628D01*
G02X181185Y632556I-1245J-841D01*
G37*
G36*
G01X148045Y629030D02*
G02X146258Y627703I-292J-1473D01*
G03X145458Y628781I-995J97D01*
G02X147245Y630108I292J1473D01*
G03X148045Y629030I995J-97D01*
G37*
G36*
G01X151355Y601742D02*
G02X151231Y604122I-975J1142D01*
G03X152447Y604186I566J824D01*
G02X152571Y601806I975J-1142D01*
G03X151355Y601742I-566J-824D01*
G37*
G36*
G01X245338Y418635D02*
G03Y417985I380J-325D01*
G02X243054I-1142J-975D01*
G03Y418635I-380J325D01*
G02X245338I1142J975D01*
G37*
G36*
G01X229915Y418625D02*
G03Y417425I800J-600D01*
G02X227511I-1202J-900D01*
G03Y418625I-800J600D01*
G02X229915I1202J900D01*
G37*
G36*
G01X115409Y417010D02*
G03Y415810I800J-600D01*
G02X113005I-1202J-900D01*
G03Y417010I-800J600D01*
G02X115409I1202J900D01*
G37*
G36*
G01X124788Y412752D02*
G03X124164I-312J-391D01*
G02Y415098I-938J1173D01*
G03X124788I312J391D01*
G02X126664I938J-1173D01*
G03X127288I312J391D01*
G02Y412752I938J-1173D01*
G03X126664I-312J-391D01*
G02X124788I-938J1173D01*
G37*
G36*
G01X183444Y419059D02*
G02X181204Y419508I-1312J-732D01*
G03X181459Y420781I-618J786D01*
G02X181598Y422451I1312J732D01*
G03Y423075I-391J312D01*
G02X181571Y423110I1176J935D01*
G03X180769Y423107I-400J-300D01*
G02X180521Y425157I-1207J894D01*
G03X181803Y425162I638J770D01*
G02X183709Y425186I968J-1149D01*
G03X184333I312J391D01*
G02X186444Y423075I938J-1173D01*
G03Y422451I391J-312D01*
G02X184333Y420340I-1173J-938D01*
G03X183709I-312J-391D01*
G02X183699Y420332I-943J1169D01*
G03X183444Y419059I618J-786D01*
G37*
G36*
G01X257628Y418535D02*
G02X257567Y416733I1170J-942D01*
G03X255968Y416787I-820J-573D01*
G02X256029Y418589I-1170J942D01*
G03X257628Y418535I820J573D01*
G37*
G36*
G01X193811Y401977D02*
G02X193700Y404059I-1135J983D01*
G03X195138Y404136I682J732D01*
G02X195249Y402054I1135J-983D01*
G03X193811Y401977I-682J-732D01*
G37*
G36*
G01X301917Y264584D02*
G03X302331Y263463I959J-283D01*
G02X300071Y262630I-820J-1259D01*
G03X299657Y263751I-959J283D01*
G02X301917Y264584I820J1259D01*
G37*
G36*
G01X246187Y260039D02*
G03Y261239I-800J600D01*
G02X247458Y263639I1202J900D01*
G03X247968Y264029I22J500D01*
G02X250635Y262797I1465J-332D01*
G03Y261597I800J-600D01*
G02X249364Y259197I-1202J-900D01*
G03X248854Y258807I-22J-500D01*
G02X246187Y260039I-1465J332D01*
G37*
G36*
G01X230547Y263039D02*
G03Y264239I-800J600D01*
G02X233192Y265556I1202J900D01*
G03X233702Y265196I480J139D01*
G02X234995Y262797I91J-1499D01*
G03Y261597I800J-600D01*
G02X233724Y259197I-1202J-900D01*
G03X233214Y258807I-22J-500D01*
G02X230547Y260039I-1465J332D01*
G03Y261239I-800J600D01*
G02Y263039I1202J900D01*
G37*
G36*
G01X314506Y257456D02*
G03X313825Y257380I-300J-399D01*
G02X313584Y259553I-1145J973D01*
G03X314265Y259629I300J399D01*
G02X314506Y257456I1145J-973D01*
G37*
G36*
G01X226526Y257800D02*
G03X226231Y257190I183J-465D01*
G02X224241Y258151I-1437J-436D01*
G03X224536Y258761I-183J465D01*
G02X224771Y260097I1437J436D01*
G03Y261297I-800J600D01*
G02X224530Y261780I1202J901D01*
G03X224020Y262140I-480J-139D01*
G02X225372Y264056I-91J1499D01*
G03X225882Y263696I480J139D01*
G02X227175Y261297I91J-1499D01*
G03Y260097I800J-600D01*
G02X226526Y257800I-1202J-901D01*
G37*
G36*
G01X310124Y248196D02*
G03X310176Y249388I-776J631D01*
G02X312586Y249283I1244J842D01*
G03X312534Y248091I776J-631D01*
G02X310124Y248196I-1244J-842D01*
G37*
G36*
G01X196576Y123797D02*
G03X195958Y122775I378J-926D01*
G02X193897Y124022I-1495J-144D01*
G03X194515Y125044I-378J926D01*
G02X196576Y123797I1495J144D01*
G37*
G36*
G01X258125Y121493D02*
G03X257960Y122673I-878J479D01*
G02X260348Y123007I1070J1054D01*
G03X260513Y121827I878J-479D01*
G02X258125Y121493I-1070J-1054D01*
G37*
G36*
G01X168991Y122109D02*
G03X168574Y121005I547J-837D01*
G02X165656Y120908I-1447J-402D01*
G03X164646Y122110I-979J203D01*
G02X161532Y123077I-155J5000D01*
G03X161050Y123138I-296J-403D01*
G02X162148Y131814I-1860J4643D01*
G03X162630Y131753I296J403D01*
G02X169053Y125060I1860J-4643D01*
G03X169174Y124484I456J-205D01*
G02X168991Y122109I-1004J-1117D01*
G37*
G36*
G01X232117Y108210D02*
G03X232644Y107129I982J-190D01*
G02X230367Y106089I-727J-1420D01*
G03X229895Y107195I-971J239D01*
G02X232117Y108210I748J1302D01*
G37*
G36*
G01X273104Y257452D02*
G02X270910Y257889I-1293J-765D01*
G03X271171Y259199I-599J800D01*
G02X271172Y260729I1293J764D01*
G03X270945Y262012I-861J509D01*
G02X271383Y264584I953J1161D01*
G03X272032Y265654I-343J940D01*
G02X274820Y266603I1489J195D01*
G03X275942Y266139I865J502D01*
G02X277188Y265919I386J-1452D01*
G03X278390Y265962I572J820D01*
G02X280795Y265153I946J-1167D01*
G03X281926Y264405I971J239D01*
G02X283188Y261822I240J-1483D01*
G03X283133Y261150I341J-366D01*
G02X281375Y258841I-1188J-919D01*
G03X280123Y258403I-379J-925D01*
G02X279381Y260525I-1312J732D01*
G03X280633Y260963I379J925D01*
G02X280923Y261331I1310J-734D01*
G03X280978Y262003I-341J366D01*
G02X280707Y262564I1188J920D01*
G03X279576Y263312I-971J-239D01*
G02X278476Y263563I-240J1483D01*
G03X277274Y263520I-572J-820D01*
G02X275029Y263933I-946J1167D01*
G03X273907Y264397I-865J-502D01*
G02X273713Y264359I-385J1452D01*
G03X273308Y263691I64J-496D01*
G02X273190Y262408I-1410J-517D01*
G03X273417Y261125I861J-509D01*
G02X273365Y258762I-953J-1161D01*
G03X273104Y257452I599J-800D01*
G37*
G36*
G01X289094Y257181D02*
G02X287756Y255801I160J-1493D01*
G03X286652Y256871I-997J76D01*
G02X286469Y259866I-161J1493D01*
G03X287453Y260835I-16J1000D01*
G02X288977Y259286I1501J-47D01*
G03X287993Y258317I16J-1000D01*
G02X287990Y258251I-1502J35D01*
G03X289094Y257181I997J-76D01*
G37*
G36*
G01X238830Y250654D02*
G02X236442Y250606I-1176J-935D01*
G03X236418Y251819I-807J591D01*
G02X238806Y251867I1176J935D01*
G03X238830Y250654I807J-591D01*
G37*
G36*
G01X301074Y248766D02*
G02X298323Y247631I-1298J-756D01*
G03X296884Y248260I-968J-253D01*
G02X295144Y250676I-708J1325D01*
G03X295157Y252116I-688J726D01*
G02X297242Y252096I1053J1071D01*
G03X297229Y250656I688J-726D01*
G02X297642Y249258I-1053J-1071D01*
G03X298541Y248865I488J-108D01*
G02X298684Y249041I1234J-856D01*
G03X298820Y250231I-728J686D01*
G02X298946Y251927I1298J756D01*
G03X299023Y253068I-780J626D01*
G02X299208Y254863I1287J774D01*
G03Y256221I-734J679D01*
G02X301412I1102J1021D01*
G03Y254863I734J-679D01*
G02X301482Y252902I-1102J-1021D01*
G03X301405Y251761I780J-626D01*
G02X301210Y249956I-1287J-774D01*
G03X301074Y248766I728J-686D01*
G37*
G36*
G01X284826Y244945D02*
G02X284787Y242961I1108J-1014D01*
G03X283286Y242991I-764J-646D01*
G02X280961Y243125I-1108J1014D01*
G03X279432Y243235I-811J-586D01*
G02X279571Y245161I-1078J1046D01*
G03X281100Y245051I811J586D01*
G02X283325Y244975I1078J-1046D01*
G03X284826Y244945I764J646D01*
G37*
G36*
G01X232812Y241263D02*
G02X230608I-1102J-1021D01*
G03Y242621I-734J679D01*
G02X232812I1102J1021D01*
G03Y241263I734J-679D01*
G37*
G36*
G01X271665Y236505D02*
G02X270272Y238539I-1405J532D01*
G03X271215Y239185I8J1000D01*
G02X271246Y239259I1400J-543D01*
G03X270955Y239932I-458J201D01*
G02X269958Y241270I503J1415D01*
G03X269499Y241743I-499J-25D01*
G02X268121Y243147I121J1497D01*
G03X267121Y244085I-998J-62D01*
G02X266864Y247067I-2J1502D01*
G03X267693Y248115I-169J986D01*
G02X267691Y248143I1497J121D01*
G03X266941Y248553I-499J-22D01*
G02X267614Y250320I-754J1299D01*
G03X268815Y249663I950J311D01*
G02X269446Y246729I378J-1454D01*
G03X268617Y245681I169J-986D01*
G01Y245680D01*
G03X269617Y244742I998J62D01*
G02X269789Y244732I-1J-1502D01*
G03X270837Y245373I112J994D01*
G02X273030Y243563I1405J-531D01*
G03X272717Y242166I525J-851D01*
G02X272924Y241020I-1259J-819D01*
G03X273388Y239944I976J-217D01*
G02X272608Y237151I-768J-1291D01*
G03X271665Y236505I-8J-1000D01*
G37*
G36*
G01X255135Y231774D02*
G02X253283Y231755I-914J-1192D01*
G03X253267Y233329I-625J781D01*
G02X255119Y233348I914J1192D01*
G03X255135Y231774I625J-781D01*
G37*
G36*
G01X136610Y131551D02*
G02X134600Y131579I-1021J-1102D01*
G03X134620Y133065I-659J752D01*
G02X136630Y133037I1021J1102D01*
G03X136610Y131551I659J-752D01*
G37*
G36*
G01X131339Y131531D02*
G02X129361I-989J-1131D01*
G03Y133036I-658J753D01*
G02X131339I989J1131D01*
G03Y131531I658J-753D01*
G37*
G36*
G01X175421Y119677D02*
G02X172771Y120988I-1208J893D01*
G03X172354Y122106I-961J278D01*
G02X174612Y122948I816J1261D01*
G03X175029Y121830I961J-278D01*
G02X175136Y121754I-815J-1261D01*
G03X176555Y121949I614J789D01*
G02X176840Y119872I1208J-892D01*
G03X175421Y119677I-614J-789D01*
G37*
G36*
G01X221351Y107630D02*
G02X219482Y106219I-368J-1456D01*
G03X218727Y107219I-1000J30D01*
G02X220596Y108630I368J1456D01*
G03X221351Y107630I1000J-30D01*
G37*
G36*
G01X197262Y106927D02*
G02X195111Y106226I-769J-1290D01*
G03X194704Y107477I-920J392D01*
G02X196855Y108178I769J1290D01*
G03X197262Y106927I920J-392D01*
G37*
G36*
G01X244600Y104281D02*
G02X242370Y103694I-870J-1224D01*
G03X242043Y104933I-906J424D01*
G02X241412Y106216I870J1224D01*
G03X240390Y107255I-999J39D01*
G02X241856Y108698I-35J1502D01*
G03X242878Y107659I999J-39D01*
G02X244273Y105520I35J-1502D01*
G03X244600Y104281I906J-424D01*
G37*
G36*
G01X219525Y102840D02*
G02X218094Y100838I-15J-1502D01*
G03X217111Y101505I-943J-332D01*
G02X216649Y101554I-65J1594D01*
G03X215568Y101142I-250J-968D01*
G02X212853Y102301I-1248J836D01*
G03X212095Y103491I-977J214D01*
G02X213732Y104220I328J1466D01*
G03X214205Y103476I435J-246D01*
G02X214619Y103450I114J-1498D01*
G03X215677Y103917I200J980D01*
G02X218576Y103554I1370J-818D01*
G03X219525Y102840I958J286D01*
G37*
G36*
G01X239955Y102357D02*
G02X238009Y101104I-455J-1432D01*
G03X237318Y102175I-993J118D01*
G02X239264Y103428I455J1432D01*
G03X239955Y102357I993J-118D01*
G37*
G36*
G01X166880Y97742D02*
G02X164167Y99266I-1183J1071D01*
G03X163637Y100453I-959J284D01*
G02X165737Y101446I643J1357D01*
G03X166318Y100283I970J-242D01*
G02X166543Y100166I-621J-1470D01*
G03X167784Y100309I531J847D01*
G02X168112Y97943I1066J-1058D01*
G03X166880Y97742I-490J-872D01*
G37*
G36*
G01X281233Y99871D02*
G02X279702Y98483I-33J-1502D01*
G03X278727Y99559I-997J76D01*
G02X277873Y102273I33J1502D01*
G03X277973Y103803I-591J807D01*
G02X279897Y103677I1037J1086D01*
G03X279797Y102147I591J-807D01*
G02X280258Y100947I-1037J-1087D01*
G03X281233Y99871I997J-76D01*
G37*
G36*
G01X173970Y104392D02*
G03X173302Y104225I-246J-435D01*
G02X170401Y104729I-1345J858D01*
G03X169813Y105108I-488J-111D01*
G02X170957Y106980I-303J1471D01*
G03X171563Y106629I482J134D01*
G02X172809Y106432I394J-1546D01*
G03X173484Y106566I267J423D01*
G02X176210Y105775I1226J-867D01*
G02X174272Y104262I-1500J-76D01*
G02X173970Y104392I439J1436D01*
G37*
G36*
G01X211801Y256984D02*
G02X209575Y255316I-773J-1288D01*
G03X208416Y256045I-968J-253D01*
G02X208266Y259015I-287J1474D01*
G03X208809Y259467I45J498D01*
G02X209094Y260218I1496J-138D01*
G03Y261401I-807J592D01*
G02X208884Y261803I1211J888D01*
G03X208380Y262140I-473J-162D01*
G02X208358Y265139I-91J1499D01*
G03X208868Y265529I22J500D01*
G02X209129Y266095I1465J-332D01*
G03X209117Y267306I-802J598D01*
G02X208854Y267832I1186J922D01*
G03X208335Y268199I-482J-132D01*
G02X208324Y271196I-109J1498D01*
G03X208843Y271578I33J499D01*
G02X211505Y270327I1460J-350D01*
G03Y269127I800J-600D01*
G02X211507Y267329I-1202J-900D01*
G03X211519Y266118I802J-598D01*
G02X211547Y264312I-1186J-922D01*
G03X211536Y263150I808J-589D01*
G02X211516Y261401I-1231J-861D01*
G03Y260218I807J-592D01*
G02X211512Y258436I-1211J-888D01*
G03X211801Y256984I804J-595D01*
G37*
G36*
G01X195408Y257351D02*
G02X193182Y257918I-1352J-654D01*
G03X193341Y258543I-291J407D01*
G02X193491Y260097I1352J654D01*
G03Y261297I-800J600D01*
G02X193454Y263047I1202J901D01*
G03X193072Y264509I-824J565D01*
G02X194974Y265007I663J1348D01*
G03X195356Y263545I824J-565D01*
G02X195895Y261297I-663J-1348D01*
G03Y260097I800J-600D01*
G02X195567Y257976I-1202J-900D01*
G03X195408Y257351I291J-407D01*
G37*
G36*
G01X186704Y255562D02*
G02X184367Y257218I-906J1198D01*
G03X184125Y257812I-476J152D01*
G02X184082Y257836I710J1323D01*
G03X182622Y257238I-497J-868D01*
G02X181923Y258946I-1446J405D01*
G03X183383Y259544I497J868D01*
G02X184898Y260639I1446J-405D01*
G03X185408Y261029I22J500D01*
G02X185671Y261597I1464J-333D01*
G03Y262797I-800J600D01*
G02X185580Y262933I1201J902D01*
G03X184479Y263394I-860J-510D01*
G02X184098Y263350I-361J1458D01*
G03X183093Y262472I-13J-1000D01*
G02X180768Y261407I-1491J184D01*
G03X180100Y261304I-278J-416D01*
G02X177782Y261274I-1171J940D01*
G03X177126Y261369I-382J-323D01*
G02X176884Y261240I-825J1255D01*
G03X176587Y260687I194J-461D01*
G02X176391Y259627I-1477J-275D01*
G03X176552Y258942I426J-261D01*
G02X174475Y258453I-796J-1274D01*
G03X174314Y259138I-426J261D01*
G02X173614Y260547I796J1274D01*
G03X173153Y261091I-498J45D01*
G02X174161Y263793I110J1498D01*
G03X175375Y263807I598J801D01*
G02X177448Y263594I926J-1183D01*
G03X178104Y263499I382J323D01*
G02X179763Y263493I825J-1255D01*
G03X180431Y263596I278J416D01*
G02X181621Y264158I1172J-940D01*
G03X182626Y265036I13J1000D01*
G02X185410Y265616I1491J-184D01*
G03X186511Y265155I860J510D01*
G02X188075Y262797I362J-1458D01*
G03Y261597I800J-600D01*
G02X186804Y259197I-1202J-900D01*
G03X186294Y258807I-22J-500D01*
G02X186260Y258681I-1466J328D01*
G03X186502Y258087I476J-152D01*
G02X186609Y258024I-708J-1325D01*
G03X187752Y258068I540J842D01*
G02X187847Y255606I906J-1198D01*
G03X186704Y255562I-540J-842D01*
G37*
G36*
G01X160028Y285137D02*
G02X159050Y286976I-1445J411D01*
G03X160322Y287653I310J950D01*
G02X161300Y285814I1445J-411D01*
G03X160028Y285137I-310J-950D01*
G37*
G36*
G01X139409Y291219D02*
G02X137657Y292465I-1484J-232D01*
G03X138466Y293603I-179J984D01*
G02X138472Y294104I1484J233D01*
G03X137689Y295263I-983J180D01*
G02X139468Y296466I301J1472D01*
G03X140251Y295307I983J-180D01*
G02X140218Y292357I-301J-1472D01*
G03X139409Y291219I179J-984D01*
G37*
G36*
G01X137694Y303175D02*
G02X135912Y302729I-602J-1376D01*
G03X135527Y304264I-786J619D01*
G02X137309Y304710I602J1376D01*
G03X137694Y303175I786J-619D01*
G37*
G36*
G01X163089Y325441D02*
G02X161341Y325730I-1072J-1052D01*
G03X161352Y326617I-226J446D01*
G02X161091Y326795I711J1323D01*
G03X160467Y326813I-323J-382D01*
G02X160536Y329158I-903J1200D01*
G03X161160Y329140I323J382D01*
G02X163107Y326860I903J-1200D01*
G03X163089Y325441I696J-718D01*
G37*
G36*
G01X152618Y377410D02*
G02X150804Y376842I-559J-1394D01*
G03X150342Y378320I-835J550D01*
G02X149622Y380500I560J1394D01*
G03X149471Y381737I-852J524D01*
G02X149833Y384142I1053J1071D01*
G03X150351Y385239I-460J888D01*
G02X152511Y384220I1469J315D01*
G03X151993Y383123I460J-888D01*
G02X151804Y382022I-1469J-315D01*
G03X151955Y380785I852J-524D01*
G02X152156Y378888I-1053J-1071D01*
G03X152618Y377410I835J-550D01*
G37*
G36*
G01X161825Y381466D02*
G02X159841Y381373I-939J-1172D01*
G03X159771Y382872I-695J719D01*
G02X161755Y382965I939J1172D01*
G03X161825Y381466I695J-719D01*
G37*
G36*
G01X201831Y258505D02*
G03X202034Y257372I906J-422D01*
G02X199615Y256939I-1057J-1067D01*
G03X199412Y258072I-906J422D01*
G02X200116Y260599I1057J1067D01*
G03X200497Y261126I-117J486D01*
G02X200989Y262364I1497J122D01*
G03X201091Y262980I-334J372D01*
G02X200961Y264136I1311J733D01*
G03X200740Y264705I-480J141D01*
G02X200293Y266860I778J1285D01*
G03Y268017I-815J579D01*
G02X202743I1225J870D01*
G03Y266860I815J-578D01*
G02X202959Y265567I-1225J-869D01*
G03X203180Y264998I480J-141D01*
G02X203407Y262597I-778J-1285D01*
G03X203305Y261981I334J-372D01*
G02X202347Y259788I-1311J-733D01*
G03X201966Y259261I117J-486D01*
G02X201831Y258505I-1497J-123D01*
G37*
G36*
G01X185473Y269430D02*
G03X184804Y269188I-215J-451D01*
G02X184085Y271173I-1364J629D01*
G03X184754Y271415I215J451D01*
G02X185473Y269430I1364J-629D01*
G37*
G36*
G01X193739Y269606D02*
G03X193154Y269385I-155J-475D01*
G02X192326Y271576I-1294J763D01*
G03X192911Y271797I155J475D01*
G02X193739Y269606I1294J-763D01*
G37*
G36*
G01X161545Y335540D02*
G03X160431Y335250I-351J-937D01*
G02X158258Y335124I-1146J970D01*
G03X157124Y335288I-684J-729D01*
G02X157475Y337725I-676J1341D01*
G03X158609Y337561I684J729D01*
G02X159811Y337627I676J-1341D01*
G03X160925Y337917I351J937D01*
G02X161545Y335540I1146J-970D01*
G37*
G36*
G01X224349Y478031D02*
G02X222403Y477223I-562J-1393D01*
G03X221856Y478540I-921J390D01*
G02X223802Y479348I562J1393D01*
G03X224349Y478031I921J-390D01*
G37*
G36*
G01X278521Y480124D02*
G02X275991Y480933I-1051J1073D01*
G03X275185Y481741I-984J-176D01*
G02X276931Y483483I267J1478D01*
G03X277737Y482675I984J176D01*
G02X278521Y482270I-267J-1478D01*
G03X279919I699J715D01*
G02X280283Y482533I1052J-1072D01*
G03X280814Y483574I-457J889D01*
G02X282985Y482467I1484J229D01*
G03X282454Y481426I457J-889D01*
G02X279919Y480124I-1484J-229D01*
G03X278521I-699J-715D01*
G37*
G36*
G01X182276Y513390D02*
G02X180313Y511396I-1045J-934D01*
G03X179003I-655J-756D01*
G02Y513515I-918J1059D01*
G03X180313I655J756D01*
G02X180470Y513632I914J-1063D01*
G03X180475Y514469I-271J420D01*
G02X182265Y514712I757J1138D01*
G03X182276Y513390I756J-655D01*
G37*
G36*
G01X170663Y518284D02*
G02X170210Y520486I-1048J932D01*
G03X171368Y520712I424J905D01*
G02X171816Y518534I1003J-929D01*
G03X170663Y518284I-405J-914D01*
G37*
G36*
G01X154828Y521708D02*
G02X152866Y521919I-1097J-974D01*
G03X153015Y523400I-590J807D01*
G02X152988Y525392I1111J1011D01*
G03X153048Y526622I-757J653D01*
G02X153171Y528467I1198J847D01*
G03X153287Y529678I-732J681D01*
G02X153751Y531623I1188J744D01*
G03X154150Y532883I-516J857D01*
G02X154256Y534184I1250J553D01*
G03X154119Y534871I-419J274D01*
G02X156129Y535216I827J1212D01*
G03X156229Y534523I403J-296D01*
G02X156125Y532277I-829J-1087D01*
G03X155748Y531010I531J-847D01*
G02X155535Y529504I-1273J-588D01*
G03X155462Y528289I755J-655D01*
G02X155374Y526530I-1216J-821D01*
G03X155337Y525300I769J-639D01*
G02X154996Y523187I-1211J-889D01*
G03X154828Y521708I580J-815D01*
G37*
G36*
G01X160095Y520878D02*
G02X160086Y522916I-916J1015D01*
G03X161419Y522921I664J748D01*
G02X161428Y520883I916J-1015D01*
G03X160095Y520878I-664J-748D01*
G37*
G36*
G01X168239Y523478D02*
G02X166495Y524846I-1402J8D01*
G03X167250Y525790I-244J969D01*
G02X169454Y526837I1367J-34D01*
G03X170254Y527307I306J395D01*
G02X170244Y527396I1353J197D01*
G03X169349Y528307I-996J-84D01*
G02X170890Y529795I142J1395D01*
G03X171769Y528868I998J66D01*
G02X172213Y528736I-162J-1357D01*
G03X173380Y528942I443J896D01*
G02X173519Y529069I1013J-969D01*
G03X173665Y530486I-625J780D01*
G02X175692Y532317I1054J871D01*
G03X177117Y532321I711J704D01*
G02X177122Y530404I977J-956D01*
G03X175697Y530400I-711J-704D01*
G02X175590Y530301I-981J953D01*
G03X175464Y528883I636J-771D01*
G02X173748Y526731I-1068J-908D01*
G03X172577Y526548I-461J-887D01*
G02X171214Y526201I-971J963D01*
G03X169952Y525460I-286J-958D01*
G02X168976Y524437I-1335J296D01*
G03X168239Y523478I263J-965D01*
G37*
G36*
G01X160245Y529084D02*
G02X158118Y529088I-1065J-857D01*
G03X158088Y530381I-777J629D01*
G02X160278Y530378I1096J975D01*
G03X160245Y529084I746J-666D01*
G37*
G36*
G01X212171Y527333D02*
G02X210183Y527529I-884J1214D01*
G03X208881Y527674I-735J-679D01*
G02X207050Y527810I-831J1209D01*
G03X206346Y527788I-341J-366D01*
G02X206300Y529903I-1089J1034D01*
G03X207004Y529912I347J359D01*
G02X209112Y529895I1046J-1029D01*
G03X210416Y529771I724J690D01*
G02X212140Y529784I871J-1224D01*
G03X213279Y529786I568J823D01*
G02X214882Y529835I839J-1203D01*
G03X215504Y529916I261J427D01*
G02X217454Y530068I1060J-1014D01*
G03X218588Y530014I606J795D01*
G02X218521Y527676I740J-1191D01*
G03X217386Y527687I-575J-818D01*
G02X215800Y527650I-822J1215D01*
G03X215178Y527569I-261J-427D01*
G02X213310Y527359I-1060J1014D01*
G03X212171Y527333I-551J-835D01*
G37*
G36*
G01X189759Y529822D02*
G02X189073Y532000I-1119J845D01*
G03X190212Y532393I309J951D01*
G02X190916Y530152I1245J-840D01*
G03X189759Y529822I-359J-933D01*
G37*
G36*
G01X185632Y535154D02*
G02X183792Y534923I-789J-1159D01*
G03X183587Y536425I-749J663D01*
G02X183402Y536566I794J1233D01*
G03X182099Y536597I-670J-743D01*
G02X180367Y536596I-867J1057D01*
G03X179064Y536564I-633J-774D01*
G02Y538744I-982J1090D01*
G03X180367Y538712I670J742D01*
G02X182097I865J-1058D01*
G03X183401Y538745I633J774D01*
G02X185461Y536660I983J-1089D01*
G03X185632Y535154I734J-679D01*
G37*
G36*
G01X231386Y533067D02*
G02X229455Y534996I-910J1020D01*
G03Y536327I-746J665D01*
G02X229456Y538146I1021J909D01*
G03Y539476I-747J665D01*
G02Y541296I1020J910D01*
G03Y542626I-747J665D01*
G02X231386Y544556I1020J910D01*
G03X232716I665J747D01*
G02X234536I910J-1020D01*
G03X235866I665J747D01*
G02X237685Y544557I910J-1020D01*
G03X239016I665J746D01*
G02X240945Y542626I909J-1021D01*
G03Y541296I747J-665D01*
G02X239016Y539365I-1020J-910D01*
G03X237685I-665J-746D01*
G02X237510Y539233I-908J1022D01*
G03Y538389I269J-422D01*
G02X237797Y536327I-734J-1153D01*
G03Y534996I746J-666D01*
G02X235866Y533067I-1021J-909D01*
G03X234536I-665J-747D01*
G02X232716I-910J1020D01*
G03X231386I-665J-747D01*
G37*
G36*
G01X168047Y537286D02*
G02X166007I-1020J-910D01*
G03Y538616I-747J665D01*
G02X166472Y540775I1020J910D01*
G03X166973Y542113I-405J914D01*
G02X168793Y541417I1270J593D01*
G03X168274Y540087I393J-920D01*
G02X168047Y538616I-1247J-561D01*
G03Y537286I747J-665D01*
G37*
G36*
G01X201028Y537309D02*
G02X199251Y538586I-1489J-197D01*
G03X200052Y539683I-192J981D01*
G02X202497Y540937I1457J170D01*
G03X203202Y540969I336J370D01*
G02X205227Y541142I1107J-1016D01*
G03X206434Y541131I611J792D01*
G02X208266Y541065I875J-1178D01*
G03X208921Y541067I326J379D01*
G02X208929Y538850I965J-1105D01*
G03X208274Y538848I-326J-379D01*
G02X206434Y538775I-965J1105D01*
G03X205227Y538764I-596J-803D01*
G02X203278Y538861I-918J1189D01*
G03X202572Y538842I-343J-363D01*
G02X201813Y538418I-1063J1011D01*
G03X201028Y537309I207J-979D01*
G37*
G36*
G01X529884Y540824D02*
G02X529516Y538526I754J-1299D01*
G03X528892Y538626I-373J-333D01*
G02X527011Y538932I-754J1299D01*
G03X526312Y538982I-375J-331D01*
G02X524253Y539087I-974J1143D01*
G03X522894Y539166I-722J-692D01*
G02X520441Y540444I-956J1159D01*
G03X519442Y541523I-997J79D01*
G02X520935Y542906I-4J1502D01*
G03X521934Y541827I997J-79D01*
G02X523023Y541363I3J-1502D01*
G03X524382Y541284I722J692D01*
G02X526465Y541118I956J-1159D01*
G03X527164Y541068I375J331D01*
G02X529260Y540924I974J-1143D01*
G03X529884Y540824I373J333D01*
G37*
G36*
G01X504948Y540318D02*
G02X503311Y541731I-1500J-83D01*
G03X504218Y542782I-91J996D01*
G02X504216Y542861I1500J78D01*
G03X503622Y543350I-500J-2D01*
G02X502847Y543405I-285J1475D01*
G03X501568Y542766I-327J-945D01*
G02X500629Y544645I-1430J459D01*
G03X501908Y545284I327J945D01*
G02X504804Y545150I1430J-459D01*
G03X505756Y544367I976J217D01*
G02X505855Y541369I-38J-1502D01*
G03X504948Y540318I91J-996D01*
G37*
G36*
G01X515938Y541800D02*
G02X515081Y539610I442J-1436D01*
G03X513922Y540063I-864J-502D01*
G02X514779Y542253I-442J1436D01*
G03X515938Y541800I864J502D01*
G37*
G36*
G01X156109Y543276D02*
G02X153850Y543359I-1164J-893D01*
G03X153896Y544633I-747J665D01*
G02X156155Y544550I1164J893D01*
G03X156109Y543276I747J-665D01*
G37*
G36*
G01X218102Y545038D02*
G02X217814Y542840I649J-1203D01*
G03X216636Y542982I-685J-728D01*
G02X216927Y545204I-690J1220D01*
G03X218102Y545038I700J714D01*
G37*
G36*
G01X160152Y542850D02*
G02X160151Y545057I-967J1103D01*
G03X161445Y545037I659J752D01*
G02Y542870I890J-1084D01*
G03X160152Y542850I-635J-773D01*
G37*
G36*
G01X502636Y551153D02*
G02X502059Y549037I702J-1328D01*
G03X500740Y549397I-852J-524D01*
G02X501317Y551513I-702J1328D01*
G03X502636Y551153I852J524D01*
G37*
G36*
G01X483578Y551706D02*
G02X481742Y550571I-369J-1456D01*
G03X481011Y551754I-977J214D01*
G02X481377Y554712I369J1456D01*
G03X482359Y555886I-3J1000D01*
G02X483841Y554646I1479J262D01*
G03X482859Y553472I3J-1000D01*
G02X482847Y552889I-1479J-261D01*
G03X483578Y551706I977J-214D01*
G37*
G36*
G01X163391Y551122D02*
G02X161269Y551108I-1055J-869D01*
G03X161229Y552405I-781J625D01*
G02X163414Y552420I1086J986D01*
G03X163391Y551122I749J-662D01*
G37*
G36*
G01X178923Y551358D02*
G02X177020Y551106I-824J-1091D01*
G03X176971Y552392I-789J614D01*
G02X179028Y554569I1112J1010D01*
G03X180287I629J777D01*
G02X182194Y554556I946J-1167D01*
G03X183463Y554546I641J768D01*
G02X183466Y552263I923J-1140D01*
G03X182197Y552251I-627J-779D01*
G02X180287Y552235I-965J1151D01*
G03X179028I-629J-777D01*
G02X178939Y552168I-947J1165D01*
G03X178923Y551358I285J-411D01*
G37*
G36*
G01X474235Y555157D02*
G02X472629Y553617I-105J-1498D01*
G03X471699Y554587I-1000J-28D01*
G02X473305Y556127I105J1498D01*
G03X474235Y555157I1000J28D01*
G37*
G36*
G01X473306Y561072D02*
G02X471794Y562587I-1502J13D01*
G03X472788Y563578I-6J1000D01*
G02X474300Y562063I1502J-13D01*
G03X473306Y561072I6J-1000D01*
G37*
G36*
G01X485339Y561214D02*
G02X484068Y562632I-1501J-66D01*
G03X485219Y563664I152J988D01*
G02X485218Y563725I1501J55D01*
G03X484066Y564709I-1000J-4D01*
G02X485340Y566199I-228J1485D01*
G03X486492Y565215I1000J4D01*
G02X487794Y564780I228J-1485D01*
G03X489080Y564658I715J699D01*
G02X488864Y562375I858J-1233D01*
G03X487578Y562497I-715J-699D01*
G02X486490Y562246I-857J1233D01*
G03X485339Y561214I-152J-988D01*
G37*
G36*
G01X483880Y572695D02*
G02X482338Y571115I-42J-1501D01*
G03X481368Y572062I-999J-53D01*
G02X482910Y573642I42J1501D01*
G03X483880Y572695I999J53D01*
G37*
G36*
G01X214521Y478042D02*
G03X213872Y477992I-295J-404D01*
G02X213697Y480264I-1063J1061D01*
G03X214346Y480314I295J404D01*
G02X214521Y478042I1063J-1061D01*
G37*
G36*
G01X138173Y514571D02*
G03X138158Y515741I-818J575D01*
G02X140594Y515772I1207J895D01*
G03X140609Y514602I818J-575D01*
G02X138173Y514571I-1207J-895D01*
G37*
G36*
G01X207046Y550042D02*
G03X206335Y550055I-362J-345D01*
G02X204217Y550075I-1049J1075D01*
G03X203512Y550081I-356J-351D01*
G02X201438Y550104I-1025J1049D01*
G03X200312Y550316I-715J-700D01*
G02X200757Y552679I-603J1337D01*
G03X201883Y552467I715J700D01*
G02X203512Y552179I604J-1337D01*
G03X204217Y552185I349J357D01*
G02X206392Y552146I1069J-1055D01*
G03X207103Y552121I368J339D01*
G02X207046Y550042I1006J-1068D01*
G37*
G36*
G01X338723Y555180D02*
G03Y554556I391J-312D01*
G02X336377I-1173J-938D01*
G03Y555180I-391J312D01*
G02Y557056I1173J938D01*
G03Y557680I-391J312D01*
G02X338723I1173J938D01*
G03Y557056I391J-312D01*
G02Y555180I-1173J-938D01*
G37*
G36*
G01X498968Y556979D02*
G03X498993Y557653I-356J351D01*
G02X501208Y557571I1145J972D01*
G03X501183Y556897I356J-351D01*
G02X498968Y556979I-1145J-972D01*
G37*
G36*
G01X515838Y561223D02*
G03X514638I-600J-800D01*
G02Y563627I-900J1202D01*
G03X515838I600J800D01*
G02Y561223I900J-1202D01*
G37*
G36*
G01X499277Y570488D02*
G03X499327Y571137I-354J354D01*
G02X501599Y570962I1211J888D01*
G03X501549Y570313I354J-354D01*
G02X501540Y568525I-1211J-888D01*
G03Y567325I800J-600D01*
G02X499136I-1202J-900D01*
G03Y568525I-800J600D01*
G02X499277Y570488I1202J900D01*
G37*
G36*
G01X489373Y568773D02*
G03X489435Y569950I-776J631D01*
G02X491858Y569822I1258J820D01*
G03X491796Y568645I776J-631D01*
G02X489373Y568773I-1258J-820D01*
G37*
G36*
G01X400047Y585974D02*
G03X399371Y585992I-348J-359D01*
G02X399430Y588206I-985J1134D01*
G03X400106Y588188I348J359D01*
G02X400047Y585974I985J-1134D01*
G37*
G36*
G01X384486Y592287D02*
G03Y591637I380J-325D01*
G02X382202I-1142J-975D01*
G03Y592287I-380J325D01*
G02X384486I1142J975D01*
G37*
G36*
G01X664773Y419023D02*
G03X665432Y418959I366J341D01*
G02X665213Y416718I880J-1217D01*
G03X664554Y416782I-366J-341D01*
G02X664773Y419023I-880J1217D01*
G37*
G36*
G01X650215Y416200D02*
G03X649555Y416159I-307J-395D01*
G02X649416Y418406I-1062J1062D01*
G03X650076Y418447I307J395D01*
G02X650215Y416200I1062J-1062D01*
G37*
G36*
G01X677419Y406373D02*
G03X677544Y407022I-306J395D01*
G02X679757Y406597I1294J763D01*
G03X679632Y405948I306J-395D01*
G02X677419Y406373I-1294J-763D01*
G37*
G36*
G01X677198Y391116D02*
G03X677552Y392214I-601J800D01*
G02X679887Y391460I1434J447D01*
G03X679533Y390362I601J-800D01*
G02X677198Y391116I-1434J-447D01*
G37*
G36*
G01X409973Y317975D02*
G03X410584Y317833I394J308D01*
G02X410057Y315556I656J-1351D01*
G03X409446Y315698I-394J-308D01*
G02X409973Y317975I-656J1351D01*
G37*
G36*
G01X275819Y294481D02*
G03X274664Y294309I-458J-889D01*
G02X274306Y296722I-1046J1078D01*
G03X275461Y296894I458J889D01*
G02X275819Y294481I1046J-1078D01*
G37*
G36*
G01X186671Y293580D02*
G03X186311Y293070I139J-480D01*
G02X184395Y294422I-1499J-91D01*
G03X184755Y294932I-139J480D01*
G02X186671Y293580I1499J91D01*
G37*
G36*
G01X402147Y294028D02*
G03X403226Y293648I812J584D01*
G02X403524Y293699I401J-1447D01*
G03X404424Y294447I-68J998D01*
G02X405982Y292573I1454J-376D01*
G03X405082Y291825I68J-998D01*
G02X402409Y291324I-1454J376D01*
G03X401330Y291704I-812J-584D01*
G02X400299Y291787I-402J1447D01*
G03X399144Y291555I-418J-908D01*
G02X398667Y293935I-1106J1016D01*
G03X399822Y294167I418J908D01*
G02X402147Y294028I1106J-1016D01*
G37*
G36*
G01X264029Y289201D02*
G03X265181Y288929I761J648D01*
G02X264625Y286572I587J-1383D01*
G03X263473Y286844I-761J-648D01*
G02X264029Y289201I-587J1383D01*
G37*
G36*
G01X272544Y284981D02*
G03X271344I-600J-800D01*
G02Y287385I-900J1202D01*
G03X272544I600J800D01*
G02X274344I900J-1202D01*
G03X275544I600J800D01*
G02X277057Y287554I900J-1202D01*
G03X277675Y287730I204J457D01*
G02X278305Y285516I1243J-843D01*
G03X277687Y285340I-204J-457D01*
G02X275544Y284981I-1243J843D01*
G03X274344I-600J-800D01*
G02X272544I-900J1202D01*
G37*
G36*
G01X395485Y282560D02*
G03X394826Y282310I-204J-457D01*
G02X394071Y284302I-1368J621D01*
G03X394730Y284552I204J457D01*
G02X395485Y282560I1368J-621D01*
G37*
G36*
G01X401934Y275763D02*
G03X401087Y274948I137J-990D01*
G02X399402Y276699I-1479J263D01*
G03X400249Y277514I-137J990D01*
G02X401934Y275763I1479J-263D01*
G37*
G36*
G01X449886Y265619D02*
G03X449396Y265162I8J-500D01*
G02X447874Y266794I-1496J130D01*
G03X448364Y267251I-8J500D01*
G02X449886Y265619I1496J-130D01*
G37*
G36*
G01X404790Y252377D02*
G03X404106Y252294I-298J-401D01*
G02X403846Y254455I-1158J957D01*
G03X404530Y254538I298J401D01*
G02X404559Y254572I1157J-958D01*
G03X404672Y255734I-752J660D01*
G02X407099Y255498I1298J755D01*
G03X406986Y254336I752J-660D01*
G02X404790Y252377I-1298J-755D01*
G37*
G36*
G01X421136Y251625D02*
G03X421232Y252772I-767J642D01*
G02X423680Y252567I1296J759D01*
G03X423584Y251420I767J-642D01*
G02X421136Y251625I-1296J-759D01*
G37*
G36*
G01X631957Y409199D02*
G02X631209Y411417I-1266J808D01*
G03X632397Y411817I345J938D01*
G02X634582Y412197I1266J-808D01*
G03X635750Y412158I611J792D01*
G02X635667Y409722I836J-1248D01*
G03X634499Y409761I-611J-792D01*
G02X633145Y409599I-836J1248D01*
G03X631957Y409199I-345J-938D01*
G37*
G36*
G01X636214Y404201D02*
G02X635677Y402068I724J-1316D01*
G03X634357Y402401I-839J-544D01*
G02X632287Y403050I-724J1316D01*
G03X631112Y403565I-895J-445D01*
G02X632037Y405674I-421J1442D01*
G03X633212Y405159I895J445D01*
G02X634894Y404534I421J-1442D01*
G03X636214Y404201I839J544D01*
G37*
G36*
G01X606978Y386978D02*
G02X606514Y389128I-1232J859D01*
G03X607846Y389416I511J859D01*
G02X608310Y387266I1232J-859D01*
G03X606978Y386978I-511J-859D01*
G37*
G36*
G01X636999Y387966D02*
G02X635492Y386578I-9J-1502D01*
G03X634502Y387654I-997J76D01*
G02X636009Y389042I9J1502D01*
G03X636999Y387966I997J-76D01*
G37*
G36*
G01X219826Y301180D02*
G02X217732Y300944I-927J-1182D01*
G03Y302202I-777J629D01*
G02X219845Y304315I1167J946D01*
G03X221103I629J777D01*
G02X222995I946J-1167D01*
G03X224253I629J777D01*
G02X226366Y302202I946J-1167D01*
G03Y300944I777J-629D01*
G02X224032I-1167J-946D01*
G03Y302202I-777J629D01*
G02X224017Y302221I1172J940D01*
G03X223231I-393J-309D01*
G02X221103Y301981I-1182J927D01*
G03X219845I-629J-777D01*
G02X219826Y301966I-940J1172D01*
G03Y301180I309J-393D01*
G37*
G36*
G01X241876Y298030D02*
G02X239782Y297794I-927J-1182D01*
G03Y299052I-777J629D01*
G02X239768Y299070I1179J931D01*
G03X238981I-393J-309D01*
G02X236633Y300943I-1181J928D01*
G03X236632Y302202I-778J629D01*
G02X236617Y302221I1172J940D01*
G03X235831I-393J-309D01*
G02X235595Y304315I-1182J927D01*
G03X236853I629J777D01*
G02X236872Y304330I940J-1172D01*
G03Y305116I-309J393D01*
G02X238753Y307458I928J1181D01*
G03X240002Y307442I635J773D01*
G02X242109Y305333I923J-1185D01*
G03X242119Y304090I788J-615D01*
G02X242126Y304081I-1182J-927D01*
G03X242918Y304090I393J310D01*
G02X245304Y304108I1200J-903D01*
G03X246086Y304099I395J307D01*
G02X246322Y304330I1162J-951D01*
G03Y305116I-309J393D01*
G02X248416Y305352I927J1182D01*
G03Y304094I777J-629D01*
G02X246295Y301988I-1167J-946D01*
G03X245043Y302004I-636J-772D01*
G02X245019Y301985I-944J1168D01*
G03X245014Y301189I300J-400D01*
G02X243153Y298831I-915J-1191D01*
G03X241895I-629J-777D01*
G02X241876Y298816I-940J1172D01*
G03Y298030I309J-393D01*
G37*
G36*
G01X295403Y290864D02*
G02Y293068I-1021J1102D01*
G03X296761I679J734D01*
G02X298803I1021J-1102D01*
G03X300161I679J734D01*
G02Y290864I1021J-1102D01*
G03X298803I-679J-734D01*
G02X296761I-1021J1102D01*
G03X295403I-679J-734D01*
G37*
G36*
G01X270129Y291949D02*
G02X267888Y292106I-1186J-863D01*
G03X267863Y292825I-359J347D01*
G02X267711Y292982I1000J1121D01*
G03X266952Y292994I-385J-319D01*
G02X264987Y292741I-1127J993D01*
G03X263811Y292697I-558J-830D01*
G02X261457Y294090I-907J1153D01*
G03X261088Y294656I-493J82D01*
G02X260586Y294891I375J1455D01*
G03X259354Y294841I-584J-812D01*
G02X259257Y297204I-974J1144D01*
G03X260489Y297254I584J812D01*
G02X262367Y297310I974J-1143D01*
G03X263535Y297285I601J799D01*
G02X265286Y297249I850J-1238D01*
G03X266486I600J800D01*
G02X268883Y295919I900J-1202D01*
G03X269252Y295394I498J-42D01*
G02X270110Y293099I-385J-1452D01*
G03X270129Y291949I828J-561D01*
G37*
G36*
G01X213526Y291730D02*
G02X211432Y291494I-927J-1182D01*
G03Y292752I-777J629D01*
G02X213545Y294865I1167J946D01*
G03X214803I629J777D01*
G02Y292531I946J-1167D01*
G03X213545I-629J-777D01*
G02X213526Y292516I-940J1172D01*
G03Y291730I309J-393D01*
G37*
G36*
G01X204095Y289381D02*
G02Y291715I-946J1167D01*
G03X205353I629J777D01*
G02X205372Y291730I940J-1172D01*
G03Y292516I-309J393D01*
G02X205142Y294655I927J1182D01*
G03X205150Y295920I-771J637D01*
G02X207476Y295906I1169J943D01*
G03X207468Y294641I771J-637D01*
G02X207466Y292752I-1169J-943D01*
G03Y291494I777J-629D01*
G02X205353Y289381I-1167J-946D01*
G03X204095I-629J-777D01*
G37*
G36*
G01X454983Y290263D02*
G02X452619Y290240I-1173J-938D01*
G03X452607Y291473I-793J609D01*
G02X454971Y291496I1173J938D01*
G03X454983Y290263I793J-609D01*
G37*
G36*
G01X296041Y285675D02*
G02X295973Y287919I-1031J1092D01*
G03X297301Y287959I641J767D01*
G02X299353Y287969I1031J-1092D01*
G03X300711I679J734D01*
G02X302753I1021J-1102D01*
G03X304111I679J734D01*
G02Y285765I1021J-1102D01*
G03X302753I-679J-734D01*
G02X300711I-1021J1102D01*
G03X299353I-679J-734D01*
G02X297369Y285715I-1020J1102D01*
G03X296041Y285675I-641J-767D01*
G37*
G36*
G01X419852Y287492D02*
G02X417570Y287785I-1264J-811D01*
G03X417734Y289060I-678J735D01*
G02X418782Y291357I1264J811D01*
G03X419634Y292449I-143J990D01*
G02X422574Y292195I1494J152D01*
G03X423290Y290956I963J-270D01*
G02X421654Y288689I-372J-1455D01*
G03X420088Y288837I-841J-540D01*
G02X420016Y288767I-1082J1041D01*
G03X419852Y287492I678J-735D01*
G37*
G36*
G01X344516Y286132D02*
G02X343914Y284263I781J-1283D01*
G03X342474Y284727I-921J-391D01*
G02X343076Y286596I-781J1283D01*
G03X344516Y286132I921J391D01*
G37*
G36*
G01X204095Y279931D02*
G02Y282265I-946J1167D01*
G03X205353I629J777D01*
G02Y279931I946J-1167D01*
G03X204095I-629J-777D01*
G37*
G36*
G01X217896Y282318D02*
G02Y279878I1003J-1220D01*
G03X216657Y279902I-635J-773D01*
G02X214803Y279931I-909J1196D01*
G03X213545I-629J-777D01*
G02Y282265I-946J1167D01*
G03X214803I629J777D01*
G02X216657Y282294I945J-1167D01*
G03X217896Y282318I604J797D01*
G37*
G36*
G01X295501Y279580D02*
G02Y281838I-991J1129D01*
G03X296819I659J752D01*
G02Y279580I991J-1129D01*
G03X295501I-659J-752D01*
G37*
G36*
G01X302716Y280277D02*
G02X300580Y280124I-993J-1127D01*
G03X300480Y281523I-761J649D01*
G02X302616Y281676I993J1127D01*
G03X302716Y280277I761J-649D01*
G37*
G36*
G01X421008Y280459D02*
G02X420629Y278117I720J-1318D01*
G03X419418Y278313I-732J-682D01*
G02X419797Y280655I-720J1318D01*
G03X421008Y280459I732J682D01*
G37*
G36*
G01X283098Y278439D02*
G02X280467Y276990I-1331J-697D01*
G03X278939Y277238I-865J-501D01*
G02X277044Y277161I-995J1125D01*
G03X275844I-600J-800D01*
G02X274044I-900J1202D01*
G03X272844I-600J-800D01*
G02X271044I-900J1202D01*
G03X269844I-600J-800D01*
G02X268044I-900J1202D01*
G03X266844I-600J-800D01*
G02X264444Y278432I-900J1202D01*
G03X264054Y278942I-500J22D01*
G02X265286Y281609I332J1465D01*
G03X266486I600J800D01*
G02X268286I900J-1202D01*
G03X269486I600J800D01*
G02X271286I900J-1202D01*
G03X272486I600J800D01*
G02X274286I900J-1202D01*
G03X275486I600J800D01*
G02X277286I900J-1202D01*
G03X278486I600J800D01*
G02X280213Y281661I900J-1202D01*
G03X281604Y281955I550J835D01*
G02X283537Y279798I1263J-813D01*
G03X283098Y278439I447J-895D01*
G37*
G36*
G01X393804Y273494D02*
G02X391436Y273371I-1136J-983D01*
G03X391372Y274598I-820J572D01*
G02X393740Y274721I1136J983D01*
G03X393804Y273494I820J-572D01*
G37*
G36*
G01X402699Y266308D02*
G02X401066Y268748I-1081J1043D01*
G03X401678Y269883I-367J930D01*
G02X402907Y271674I1470J308D01*
G03X403747Y272689I-160J987D01*
G02X405489Y271248I1501J42D01*
G03X404649Y270233I160J-987D01*
G02X404643Y270046I-1501J-45D01*
G03X405398Y268979I995J-96D01*
G02X404066Y266376I-360J-1458D01*
G03X402699Y266308I-647J-762D01*
G37*
G36*
G01X420987Y262827D02*
G02X419358Y261251I-129J-1496D01*
G03X418446Y262195I-999J-52D01*
G02X420075Y263771I129J1496D01*
G03X420987Y262827I999J52D01*
G37*
G36*
G01X429055Y259680D02*
G02X426814Y259947I-1238J-851D01*
G03X426970Y261258I-668J744D01*
G02X429211Y260991I1238J851D01*
G03X429055Y259680I668J-744D01*
G37*
G36*
G01X393493Y258101D02*
G02X391932Y259752I-1495J150D01*
G03X392883Y260651I-44J999D01*
G02X394444Y259000I1495J-150D01*
G03X393493Y258101I44J-999D01*
G37*
G36*
G01X400576Y258019D02*
G02X398200Y258256I-1278J-788D01*
G03X398320Y259463I-731J682D01*
G02X400696Y259226I1278J788D01*
G03X400576Y258019I731J-682D01*
G37*
G36*
G01X428233Y250862D02*
G02X426217Y251303I-1241J-846D01*
G03X426527Y252723I-516J856D01*
G02X428543Y252282I1241J846D01*
G03X428233Y250862I516J-856D01*
G37*
G36*
G01X400389Y251116D02*
G02X398366Y249885I-531J-1405D01*
G03X397727Y250936I-993J116D01*
G02X399750Y252167I531J1405D01*
G03X400389Y251116I993J-116D01*
G37*
G36*
G01X420179Y243587D02*
G02X417817Y243485I-1141J-976D01*
G03X417764Y244718I-813J583D01*
G02X420126Y244820I1141J976D01*
G03X420179Y243587I813J-583D01*
G37*
G36*
G01X425060Y242702D02*
G02X423503Y241564I-99J-1499D01*
G03X422599Y242802I-971J240D01*
G02X424156Y243940I99J1499D01*
G03X425060Y242702I971J-240D01*
G37*
G36*
G01X234852Y354921D02*
G02X232505Y354874I-1155J-960D01*
G03X232480Y356122I-794J608D01*
G02X234827Y356169I1155J960D01*
G03X234852Y354921I794J-608D01*
G37*
G36*
G01X215798Y379844D02*
X210119D01*
X206028Y383934D01*
G03X204745Y384044I-707J-707D01*
G02X203441Y386709I-865J1229D01*
G03X203794Y387150I-145J478D01*
G02X207205Y388418I1996J-147D01*
G01X211777Y383846D01*
X212181D01*
G03X212681Y384346I0J500D01*
G01Y384453D01*
X212637Y384551D01*
G02X213202Y386432I1371J614D01*
G03X213513Y387806I-537J844D01*
G02X216234Y388203I1273J797D01*
G03X217010Y386955I964J-266D01*
G02X218048Y386404I-378J-1965D01*
G01X219962Y384490D01*
X221088D01*
G03X222077Y385338I0J1000D01*
G02X224837Y385901I1484J-230D01*
G03X226393Y385722I849J528D01*
G01X227314Y386642D01*
G02X230144Y383812I1415J-1415D01*
G01X226820Y380488D01*
X218304D01*
X217727Y381065D01*
G03X217019I-354J-354D01*
G01X215798Y379844D01*
G37*
G36*
G01X251769Y383766D02*
G02X249408Y383952I-1108J1014D01*
G03X247970Y384199I-835J-551D01*
G02X246158Y384200I-905J1199D01*
G03X245529Y384180I-302J-398D01*
G02X245453Y386513I-983J1136D01*
G03X246082Y386533I302J398D01*
G02X248318Y386226I983J-1135D01*
G03X249756Y385979I835J551D01*
G02X251415Y386079I905J-1199D01*
G03X252654Y386269I501J865D01*
G02X253008Y383956I1108J-1014D01*
G03X251769Y383766I-501J-865D01*
G37*
G36*
G01X220511Y391837D02*
G02X220355Y389615I927J-1182D01*
G03X219017Y389709I-721J-693D01*
G02X219173Y391931I-927J1182D01*
G03X220511Y391837I721J693D01*
G37*
G36*
G01X239035Y325239D02*
G03X238544Y325647I-491J-92D01*
G02X238422Y328646I1J1502D01*
G03X238878Y329098I-42J498D01*
G02X241503Y327970I1496J-138D01*
G03X241558Y326594I752J-659D01*
G02X239035Y325239I-1047J-1077D01*
G37*
G36*
G01X240513Y333142D02*
G03X240001Y332770I-28J-499D01*
G02X237347Y334050I-1453J378D01*
G03X237351Y335244I-800J600D01*
G02X238304Y337616I1209J892D01*
G03X238718Y338084I-85J493D01*
G02X238800Y338507I1500J-71D01*
G03X238569Y339111I-472J166D01*
G02X240708Y339931I722J1317D01*
G03X240939Y339327I472J-166D01*
G02X241430Y337123I-721J-1317D01*
G03X241582Y335777I807J-590D01*
G02X240513Y333142I-984J-1135D01*
G37*
G36*
G01X237680Y386917D02*
G03X237749Y386296I423J-267D01*
G02X235419Y386039I-1062J-1062D01*
G03X235350Y386660I-423J267D01*
G02X237680Y386917I1062J1062D01*
G37*
G36*
G01X230799Y389423D02*
G03X230562Y390075I-457J203D01*
G02X232596Y390815I661J1349D01*
G03X232833Y390163I457J-203D01*
G02X230799Y389423I-661J-1349D01*
G37*
G36*
G01X241496Y390646D02*
G03X241020Y390241I15J-500D01*
G02X239501Y392029I-1474J287D01*
G03X239977Y392434I-15J500D01*
G02X242872Y392634I1474J-287D01*
G03X243493Y392319I473J162D01*
G02X242519Y390398I447J-1434D01*
G03X241898Y390713I-473J-162D01*
G02X241496Y390646I-446J1434D01*
G37*
G36*
G01X211028Y500444D02*
G03X209961Y500025I-234J-972D01*
G02X209061Y502316I-1251J831D01*
G03X210128Y502735I234J972D01*
G02X211028Y500444I1251J-831D01*
G37*
G36*
G01X278661Y532963D02*
G02X276596Y535028I-936J1129D01*
G03Y536305I-770J639D01*
G02Y538178I1129J936D01*
G03Y539454I-770J638D01*
G02Y541328I1129J937D01*
G03Y542604I-770J638D01*
G02X278661Y544670I1129J936D01*
G03X279938I638J770D01*
G02X281811I936J-1129D01*
G03X283087I638J770D01*
G02X284961I937J-1129D01*
G03X286237I638J770D01*
G02X288110I937J-1129D01*
G03X289387I639J770D01*
G02X291452Y542604I936J-1130D01*
G03Y541328I770J-638D01*
G02X291498Y541270I-1126J-940D01*
G03X292298I400J299D01*
G02X292536Y539262I1175J-879D01*
G03X291260I-638J-770D01*
G02X289387I-936J1129D01*
G03X288110I-638J-770D01*
G02X286045Y541328I-936J1130D01*
G03Y542604I-770J638D01*
G02X285999Y542662I1126J940D01*
G03X285199I-400J-299D01*
G02X283087Y542412I-1175J879D01*
G03X281811I-638J-770D01*
G02X279938I-937J1129D01*
G03X278661I-639J-770D01*
G02X278604Y542366I-949J1118D01*
G03Y541566I299J-400D01*
G02X278854Y539454I-879J-1175D01*
G03Y538178I770J-638D01*
G02X278899Y538120I-1136J-928D01*
G03X279700I401J300D01*
G02X282003Y536305I1174J-879D01*
G03Y535028I770J-638D01*
G02X282049Y534971I-1118J-949D01*
G03X282849I400J299D01*
G02X284961Y535221I1175J-879D01*
G03X286237I638J770D01*
G02X288110I937J-1129D01*
G03X289387I639J770D01*
G02X291260I936J-1129D01*
G03X292536I638J770D01*
G02Y532963I937J-1129D01*
G03X291260I-638J-770D01*
G02X289387I-936J1129D01*
G03X288110I-638J-770D01*
G02X286237I-936J1129D01*
G03X284961I-638J-770D01*
G02X283087I-937J1129D01*
G03X281811I-638J-770D01*
G02X279938I-937J1129D01*
G03X278661I-639J-770D01*
G37*
G36*
G01X262909Y532959D02*
G02X260843Y535024I-936J1129D01*
G03Y536301I-770J638D01*
G02Y538174I1129J936D01*
G03Y539450I-770J638D01*
G02X262909Y541516I1129J937D01*
G03X264185I638J770D01*
G02X266059I937J-1129D01*
G03X267335I638J770D01*
G02X269401Y539450I937J-1129D01*
G03Y538174I770J-638D01*
G02Y536301I-1129J-936D01*
G03Y535024I770J-638D01*
G02X267335Y532959I-1130J-936D01*
G03X266059I-638J-770D01*
G02X264185I-937J1129D01*
G03X262909I-638J-770D01*
G37*
G36*
G01X250311D02*
G02X248245Y535024I-936J1129D01*
G03Y536301I-770J638D01*
G02Y538174I1129J936D01*
G03Y539450I-770J638D01*
G02X250311Y541516I1129J937D01*
G03X251587I638J770D01*
G02X253460I937J-1129D01*
G03X254737I639J770D01*
G02X256802Y539450I936J-1130D01*
G03Y538174I770J-638D01*
G02Y536301I-1129J-936D01*
G03Y535024I770J-638D01*
G02X254737Y532959I-1129J-936D01*
G03X253460I-638J-770D01*
G02X251587I-936J1129D01*
G03X250311I-638J-770D01*
G37*
G36*
G01Y523510D02*
G02X248245Y525576I-937J1129D01*
G03Y526852I-770J638D01*
G02X250311Y528918I1129J937D01*
G03X251587I638J770D01*
G02X253460I937J-1129D01*
G03X254737I639J770D01*
G02X256802Y526852I936J-1130D01*
G03Y525576I770J-638D01*
G02X254737Y523510I-1129J-936D01*
G03X253460I-638J-770D01*
G02X251587I-936J1129D01*
G03X250311I-638J-770D01*
G37*
G36*
G01X262909Y520360D02*
G02X260843Y522426I-937J1129D01*
G03Y523702I-770J638D01*
G02Y525576I1129J937D01*
G03Y526852I-770J638D01*
G02X262909Y528918I1129J937D01*
G03X264185I638J770D01*
G02X266059I937J-1129D01*
G03X267335I638J770D01*
G02X269401Y526852I937J-1129D01*
G03Y525576I770J-638D01*
G02Y523702I-1129J-937D01*
G03Y522426I770J-638D01*
G02X267335Y520360I-1129J-937D01*
G03X266059I-638J-770D01*
G02X264185I-937J1129D01*
G03X262909I-638J-770D01*
G37*
G36*
G01X275514Y501458D02*
G02X275511Y503726I-932J1133D01*
G03X276780Y503728I633J774D01*
G02X276783Y501460I932J-1133D01*
G03X275514Y501458I-633J-774D01*
G37*
G36*
G01X262909Y501462D02*
G02X260843Y503528I-937J1129D01*
G03Y504804I-770J638D01*
G02Y506678I1129J937D01*
G03Y507954I-770J638D01*
G02X262908Y510020I1129J936D01*
G03X264185I639J770D01*
G02X266058I937J-1129D01*
G03X267335I639J769D01*
G02X267393Y510065I928J-1136D01*
G03Y510866I-300J401D01*
G02X269209Y513169I879J1174D01*
G03X270485I638J770D01*
G02Y510911I937J-1129D01*
G03X269209I-638J-770D01*
G02X269151Y510866I-928J1136D01*
G03Y510065I300J-400D01*
G02X269401Y507954I-879J-1174D01*
G03Y506678I770J-638D01*
G02X267335Y504612I-1129J-937D01*
G03X266059I-638J-770D01*
G02X266001Y504566I-940J1126D01*
G03Y503766I299J-400D01*
G02X264185Y501462I-879J-1175D01*
G03X262909I-638J-770D01*
G37*
G36*
G01X244011D02*
G02Y503720I-936J1129D01*
G03X245288I638J770D01*
G02X247161I936J-1129D01*
G03X248437I638J770D01*
G02X248495Y503766I940J-1126D01*
G03Y504566I-299J400D01*
G02X248245Y506678I879J1175D01*
G03Y507954I-770J638D01*
G02X250311Y510020I1129J937D01*
G03X251587I638J770D01*
G02X251645Y510065I928J-1136D01*
G03Y510866I-300J401D01*
G02X253460Y513169I879J1174D01*
G03X254737I639J770D01*
G02X256802Y511104I936J-1129D01*
G03Y509827I770J-638D01*
G02Y507954I-1129J-937D01*
G03Y506678I770J-638D01*
G02Y504804I-1129J-937D01*
G03Y503528I770J-638D01*
G02X254737Y501462I-1129J-936D01*
G03X253460I-638J-770D01*
G02X251587I-936J1129D01*
G03X250311I-638J-770D01*
G02X248437I-937J1129D01*
G03X247161I-638J-770D01*
G02X245288I-937J1129D01*
G03X244011I-638J-770D01*
G37*
G36*
G01X228233Y501472D02*
G02X226168Y503543I-949J1119D01*
G03X226185Y504819I-761J648D01*
G02X226037Y505041I1141J921D01*
G03X225117Y504942I-440J-238D01*
G02X224679Y506454I-1408J412D01*
G03X226145Y506611I661J750D01*
G02X226199Y506680I1182J-869D01*
G03X226200Y507958I-769J640D01*
G02X228456Y507955I1129J936D01*
G03X228455Y506677I769J-640D01*
G02X228501Y506620I-1118J-949D01*
G03X229301I400J299D01*
G02X231605Y504804I1175J-879D01*
G03Y503528I770J-638D01*
G02X231651Y503470I-1126J-940D01*
G03X232451I400J299D01*
G02X232689Y501462I1175J-879D01*
G03X231413I-638J-770D01*
G02X229527Y501472I-937J1129D01*
G03X228233I-647J-762D01*
G37*
G36*
G01X272551Y497240D02*
G02X270291Y497221I-1122J-945D01*
G03X270280Y498496I-776J631D01*
G02X272540Y498515I1122J945D01*
G03X272551Y497240I776J-631D01*
G37*
G36*
G01X300000Y497340D02*
G02X298713Y495992I209J-1487D01*
G03X297579Y497076I-996J94D01*
G02X298866Y498424I-209J1487D01*
G03X300000Y497340I996J-94D01*
G37*
G36*
G01X288664Y497005D02*
G02X286846Y496604I-655J-1352D01*
G03X286519Y498132I-774J633D01*
G02X286237Y498316I655J1312D01*
G03X284960I-638J-770D01*
G02X282895Y500382I-936J1130D01*
G03Y501658I-770J638D01*
G02X285153I1129J937D01*
G03Y500382I770J-638D01*
G02X285198Y500324I-1136J-928D01*
G03X285999I400J300D01*
G02X288319Y498529I1174J-879D01*
G03X288664Y497005I781J-624D01*
G37*
G36*
G01X266761Y669303D02*
G02X264557Y669542I-1211J-888D01*
G03X264702Y670884I-661J750D01*
G02X266856Y672941I1211J888D01*
G03X268373Y673262I628J778D01*
G02X268766Y671406I1336J-687D01*
G03X267249Y671085I-628J-778D01*
G02X266906Y670645I-1336J687D01*
G03X266761Y669303I661J-750D01*
G37*
G36*
G01X327258Y324791D02*
Y341991D01*
X328435Y343168D01*
X336725D01*
X337692Y342201D01*
Y324641D01*
X336835Y323784D01*
X328265D01*
X327258Y324791D01*
G37*
G36*
G01X336419Y371484D02*
G03X335792Y371467I-303J-397D01*
G02X335727Y373804I-976J1142D01*
G03X336354Y373821I303J397D01*
G02X336419Y371484I976J-1142D01*
G37*
G36*
G01X320321Y373305D02*
G03X321477Y373220I638J770D01*
G02X321297Y370779I778J-1285D01*
G03X320141Y370864I-638J-770D01*
G02X320321Y373305I-778J1285D01*
G37*
G36*
G01X282427Y340124D02*
G03X282430Y338958I814J-581D01*
G02X279990Y338952I-1218J-879D01*
G03X279987Y340118I-814J581D01*
G02X282427Y340124I1218J879D01*
G37*
G36*
G01X359114Y329662D02*
G03X358612Y329174I-2J-500D01*
G02X356098Y330320I-1502J36D01*
G03X356070Y331823I-673J739D01*
G02X358535Y333116I970J1147D01*
G03X359054Y332665I497J48D01*
G02X359114Y329662I66J-1501D01*
G37*
G36*
G01X354859Y315236D02*
G03X356031Y315162I637J771D01*
G02X355879Y312735I804J-1269D01*
G03X354707Y312809I-637J-771D01*
G02X354859Y315236I-804J1269D01*
G37*
G36*
G01X352848Y419363D02*
G02X352614Y421422I-1198J907D01*
G03X354052Y421586I641J767D01*
G02X354286Y419527I1198J-907D01*
G03X352848Y419363I-641J-767D01*
G37*
G36*
G01X316661Y385740D02*
G02X314314Y385627I-1129J-991D01*
G03X314255Y386872I-811J585D01*
G02X316602Y386985I1129J991D01*
G03X316661Y385740I811J-585D01*
G37*
G36*
G01X344646Y383386D02*
G02X342690Y383210I-876J-1220D01*
G03X342554Y384717I-719J695D01*
G02X344510Y384893I876J1220D01*
G03X344646Y383386I719J-695D01*
G37*
G36*
G01X297784Y376015D02*
G02X296930Y373773I418J-1443D01*
G03X295806Y374201I-846J-532D01*
G02X294402Y374511I-418J1443D01*
G03X292922Y374324I-656J-754D01*
G02X292672Y376310I-1236J853D01*
G03X294152Y376497I656J754D01*
G02X296660Y376443I1236J-853D01*
G03X297784Y376015I846J532D01*
G37*
G36*
G01X292497Y353588D02*
G02X292470Y351318I970J-1147D01*
G03X291160Y351334I-664J-748D01*
G02X289088Y351460I-970J1146D01*
G03X287697Y351535I-734J-679D01*
G02X285538Y351730I-986J1133D01*
G03X283982Y351738I-781J-624D01*
G02X283991Y353625I-1164J949D01*
G03X285547Y353617I781J624D01*
G02X285559Y353632I1179J-931D01*
G03X285283Y355145I-767J642D01*
G02X287172Y355490I737J1309D01*
G03X287448Y353977I767J-642D01*
G02X287813Y353688I-739J-1308D01*
G03X289204Y353613I734J679D01*
G02X291187Y353604I986J-1133D01*
G03X292497Y353588I664J748D01*
G37*
G36*
G01X255896Y325525D02*
G02X253571Y325780I-1265J-809D01*
G03X253640Y326404I-353J355D01*
G02X253788Y328217I1265J809D01*
G03X253811Y328858I-372J334D01*
G02Y330700I1187J921D01*
G03X253767Y331363I-395J307D01*
G02X253875Y333604I1052J1072D01*
G03X253952Y334305I-314J389D01*
G02X253906Y336122I1172J939D01*
G03X253860Y337351I-811J585D01*
G02X256227Y337440I1149J967D01*
G03X256273Y336211I811J-585D01*
G02X256068Y334075I-1149J-968D01*
G03X255991Y333374I314J-389D01*
G02X256006Y331514I-1172J-940D01*
G03X256050Y330851I395J-307D01*
G02X256115Y328775I-1052J-1072D01*
G03X256092Y328134I372J-334D01*
G02X255965Y326149I-1187J-921D01*
G03X255896Y325525I353J-355D01*
G37*
G36*
G01X356837Y309000D02*
G02X356024Y307006I563J-1392D01*
G03X354733Y307532I-916J-401D01*
G02X355546Y309526I-563J1392D01*
G03X356837Y309000I916J401D01*
G37*
G36*
G01X340742Y620318D02*
G03Y619668I380J-325D01*
G02X338458I-1142J-975D01*
G03Y620318I-380J325D01*
G02X340742I1142J975D01*
G37*
G36*
G01X340526Y613169D02*
G03Y612519I380J-325D01*
G02X338242I-1142J-975D01*
G03Y613169I-380J325D01*
G02X340526I1142J975D01*
G37*
G36*
G01X340789Y605000D02*
G03Y604376I391J-312D01*
G02X338443I-1173J-938D01*
G03Y605000I-391J312D01*
G02X340789I1173J938D01*
G37*
G36*
G01X339828Y639466D02*
G02X338889Y637666I512J-1412D01*
G03X337582Y638347I-966J-259D01*
G02X338521Y640147I-512J1412D01*
G03X339828Y639466I966J259D01*
G37*
G36*
G01X302869Y700913D02*
G03Y700289I391J-312D01*
G02X300523I-1173J-938D01*
G03Y700913I-391J312D01*
G02X302869I1173J938D01*
G37*
G36*
G01X375294Y496173D02*
G02X374020Y498077I-1444J412D01*
G03X375096Y498797I114J994D01*
G02X376370Y496893I1444J-412D01*
G03X375294Y496173I-114J-994D01*
G37*
G36*
G01X375297Y480362D02*
G02X372708Y479232I-1090J-1033D01*
G03X371458Y480135I-998J-65D01*
G02X371837Y482886I-378J1454D01*
G03X373085Y483082I504J864D01*
G02X375296Y481049I1118J-1003D01*
G03X375297Y480362I364J-343D01*
G37*
G36*
G01X528073Y176691D02*
G02X525276Y176409I-1452J388D01*
G02X527261Y178440I1345J671D01*
G03X527820Y178699I172J362D01*
G02X530617Y178981I1452J-388D01*
G02X528632Y176950I-1345J-671D01*
G03X528073Y176691I-172J-362D01*
G37*
G36*
G01X534693Y178338D02*
G02X532461Y178550I-1211J-889D01*
G03X532587Y179875I-680J733D01*
G02X534819Y179663I1211J889D01*
G03X534693Y178338I680J-733D01*
G37*
G36*
G01X585214Y320933D02*
G02X583609Y322700I-1477J271D01*
G03X584507Y323517I-86J997D01*
G02X586112Y321750I1477J-271D01*
G03X585214Y320933I86J-997D01*
G37*
G36*
G01X578141Y311262D02*
G02X576671Y312948I-1491J184D01*
G03X577677Y313825I14J1000D01*
G02X580659I1491J-184D01*
G03X581651Y312948I992J123D01*
G02X581824Y312938I0J-1502D01*
G03X582374Y313522I58J497D01*
G02X584030Y312291I1479J261D01*
G03X583149Y311357I117J-993D01*
G02X580159Y311262I-1499J89D01*
G03X579167Y312139I-992J-123D01*
G01X579147D01*
G03X578141Y311262I-14J-1000D01*
G37*
G36*
G01X633195Y306516D02*
G02X631052Y305966I-819J-1259D01*
G03X630883Y306621I-441J235D01*
G02X631444Y309360I819J1259D01*
G03X632272Y310383I-171J985D01*
G02Y310502I1501J60D01*
G03X631612Y311485I-999J42D01*
G02X631791Y314363I510J1413D01*
G03X632173Y314937I-111J488D01*
G02X635137Y315424I1479J262D01*
G03X635936Y314593I988J151D01*
G02X637137Y312891I-284J-1475D01*
G03X637464Y312344I494J-76D01*
G02X637584Y312295I-507J-1414D01*
G03X638867Y312710I414J910D01*
G02X641352Y312893I1304J-745D01*
G03X642924I786J618D01*
G02Y311037I1181J-928D01*
G03X641352I-786J-618D01*
G02X639549Y310598I-1181J928D01*
G03X638266Y310183I-414J-910D01*
G02X636179Y309646I-1304J745D01*
G03X634904Y309451I-522J-853D01*
G02X634031Y308959I-1132J988D01*
G03X633203Y307936I171J-985D01*
G02X633026Y307171I-1501J-56D01*
G03X633195Y306516I441J-235D01*
G37*
G36*
G01X644604Y294730D02*
G02X642092Y293236I-1434J-448D01*
G03X641413Y293271I-358J-349D01*
G02X639696Y295722I-965J1151D01*
G03X639891Y296384I-250J433D01*
G02X642093Y298297I1336J686D01*
G03X643246Y298298I576J818D01*
G02X644980Y295845I867J-1227D01*
G03X644604Y294730I578J-816D01*
G37*
G36*
G01X625220Y293838D02*
G02X623376Y293706I-837J-1247D01*
G03X623264Y295278I-670J742D01*
G02X625108Y295410I837J1247D01*
G03X625220Y293838I670J-742D01*
G37*
G36*
G01X558407Y284186D02*
G02X558224Y286228I-1185J923D01*
G03X559680Y286357I668J744D01*
G02X559863Y284315I1185J-923D01*
G03X558407Y284186I-668J-744D01*
G37*
G36*
G01X641977Y285927D02*
G02X641772Y283814I955J-1159D01*
G03X641067Y283883I-387J-317D01*
G02X641272Y285996I-955J1159D01*
G03X641977Y285927I387J317D01*
G37*
G36*
G01X576917Y283476D02*
G02X574831I-1043J-1081D01*
G03Y284914I-695J719D01*
G02X574933Y287166I1043J1081D01*
G03Y288724I-627J779D01*
G02X574702Y290834I941J1171D01*
G03X574704Y292081I-781J625D01*
G02X574745Y294000I1176J935D01*
G03X574752Y294647I-378J328D01*
G02X577043Y294622I1156J959D01*
G03X577036Y293975I378J-328D01*
G02X577052Y292077I-1156J-959D01*
G03X577050Y290830I781J-625D01*
G02X576815Y288724I-1176J-935D01*
G03Y287166I627J-779D01*
G02X576917Y284914I-941J-1171D01*
G03Y283476I695J-719D01*
G37*
G36*
G01X531588Y279786D02*
G02X530256Y281597I-1469J315D01*
G03X531325Y282383I91J996D01*
G02X532657Y280572I1469J-315D01*
G03X531588Y279786I-91J-996D01*
G37*
G36*
G01X601845Y267854D02*
G02Y269736I-1171J941D01*
G03X603403I779J627D01*
G02X603458Y269801I1174J-938D01*
G03X603538Y271039I-742J670D01*
G02X605890Y270887I1236J854D01*
G03X605810Y269649I742J-670D01*
G02X605962Y269369I-1237J-853D01*
G03X606886I462J191D01*
G02X607163Y267784I1388J-574D01*
G03X605685I-739J-673D01*
G02X603403Y267854I-1111J1011D01*
G03X601845I-779J-627D01*
G37*
G36*
G01X596750Y270187D02*
G02X595078Y268824I-176J-1492D01*
G03X594198Y269903I-996J86D01*
G02X595870Y271266I176J1492D01*
G03X596750Y270187I996J-86D01*
G37*
G36*
G01X595025Y263360D02*
G02X592868Y263510I-1151J-965D01*
G03X592916Y264203I-335J371D01*
G02X595073Y264053I1151J965D01*
G03X595025Y263360I335J-371D01*
G37*
G36*
G01X602045Y248854D02*
G02Y250736I-1171J941D01*
G03X603603I779J627D01*
G02X605825Y250868I1171J-941D01*
G03X607223I699J715D01*
G02Y248722I1051J-1073D01*
G03X605825I-699J-715D01*
G02X603603Y248854I-1051J1073D01*
G03X602045I-779J-627D01*
G37*
G36*
G01X593798Y248251D02*
G02X591928Y248258I-939J-1172D01*
G03X591934Y249823I-620J785D01*
G02X593804Y249816I939J1172D01*
G03X593798Y248251I620J-785D01*
G37*
G36*
G01X537455Y248211D02*
G02X535214Y247626I-879J-1218D01*
G03X534893Y248858I-907J422D01*
G02X536804Y251167I879J1218D01*
G03X538269Y251266I687J727D01*
G02X538103Y249635I1169J-943D01*
G03X537187Y249573I-445J-229D01*
G02X537134Y249443I-1416J501D01*
G03X537455Y248211I907J-422D01*
G37*
G36*
G01X610927Y238853D02*
G02X608918Y237562I-512J-1412D01*
G03X608262Y238583I-997J81D01*
G02X610271Y239874I512J1412D01*
G03X610927Y238853I997J-81D01*
G37*
G36*
G01X606306Y237658D02*
G02X604442Y237154I-632J-1363D01*
G03X604042Y238632I-821J571D01*
G02X603585Y238961I634J1362D01*
G03X602066Y238881I-725J-688D01*
G02X599682I-1192J914D01*
G03X598163Y238961I-794J-608D01*
G02X597479Y238549I-1089J1034D01*
G03X596799Y237270I269J-963D01*
G02X594969Y238241I-1425J-475D01*
G03X595649Y239520I-269J963D01*
G02X595596Y239728I1425J474D01*
G03X594693Y239924I-492J-89D01*
G02X594759Y241533I-1234J856D01*
G03X596204Y241219I865J501D01*
G02X598266Y240909I870J-1224D01*
G03X599785Y240829I794J608D01*
G02X601963I1089J-1034D01*
G03X603482Y240909I725J688D01*
G02X605906Y239136I1192J-914D01*
G03X606306Y237658I821J-571D01*
G37*
G36*
G01X562713Y229780D02*
G02X561153Y231651I-1455J373D01*
G03X562051Y232400I-71J998D01*
G02X564942Y232467I1455J-373D01*
G03X566038Y231770I956J293D01*
G02X564812Y229843I210J-1487D01*
G03X563716Y230540I-956J-293D01*
G02X563611Y230529I-209J1487D01*
G03X562713Y229780I71J-998D01*
G37*
G36*
G01X553209Y230079D02*
G02X550804Y228286I-1159J-955D01*
G03X549728Y228697I-830J-558D01*
G02X548176Y231080I-370J1456D01*
G03X547510Y231807I-394J308D01*
G02X546917Y231581I-819J1259D01*
G03X546492Y231087I75J-494D01*
G02X544763Y232571I-1502J-1D01*
G03X545188Y233065I-75J494D01*
G02X545374Y233790I1502J1D01*
G03X545091Y235077I-876J482D01*
G02X547297Y235563I890J1210D01*
G03X547580Y234276I876J-482D01*
G02X547764Y234116I-890J-1210D01*
G03X548463Y234101I357J350D01*
G02X550727Y233851I1025J-1098D01*
G03X551385Y233698I413J283D01*
G02X553237Y231384I735J-1310D01*
G03X553209Y230079I744J-669D01*
G37*
G36*
G01X513223Y206862D02*
G02X512849Y208967I-1226J868D01*
G03X513540Y209090I283J412D01*
G02X513914Y206985I1226J-868D01*
G03X513223Y206862I-283J-412D01*
G37*
G36*
G01X560410Y207487D02*
G02X560676Y206535I1499J-94D01*
G03X559077Y206593I-821J-571D01*
G02X556739Y206595I-1168J944D01*
G03X555140Y206541I-779J-627D01*
G02X555079Y208343I-1231J860D01*
G03X556678Y208397I779J627D01*
G02X556918Y208665I1231J-861D01*
G03X557120Y209922I-661J751D01*
G02X557072Y210011I1297J757D01*
G03X556007Y210549I-894J-447D01*
G02X557094Y212700I-257J1480D01*
G03X558159Y212162I894J447D01*
G02X559407Y209554I257J-1480D01*
G03X559205Y208297I661J-751D01*
G02X559411Y207523I-1296J-759D01*
G03X560410Y207487I500J-5D01*
G37*
G36*
G01X532606Y205001D02*
G02X531492Y207616I-107J1499D01*
G03X531454Y208241I-269J297D01*
G02X533139Y210730I866J1229D01*
G02X533283Y208316I-817J-1260D01*
G02X533131Y208205I-961J1156D01*
G03X533152Y207855I108J-169D01*
G02X532606Y205001I-652J-1355D01*
G37*
G36*
G01X570612Y194020D02*
G02Y196378I-930J1179D01*
G03X571852I620J785D01*
G02Y194020I930J-1179D01*
G03X570612I-620J-785D01*
G37*
G36*
G01X608350Y193782D02*
Y200932D01*
X608393Y201204D01*
G02X615053Y200690I3309J-532D01*
G02X615054Y200656I-3348J-115D01*
G01Y193991D01*
G02X608380Y193555I-3352J5D01*
G01X608350Y193782D01*
G37*
G36*
G01X526714Y192195D02*
G02X524780Y193117I-1421J-490D01*
G03X525022Y193625I-137J377D01*
G02X526937Y195536I1421J491D01*
G02X527927Y194355I-494J-1420D01*
G03X528590Y194119I396J63D01*
G02X528108Y192760I1002J-1120D01*
G03X527445Y192996I-396J-63D01*
G02X526956Y192703I-1003J1119D01*
G03X526714Y192195I137J-377D01*
G37*
G36*
G01X515814Y192719D02*
G02X514071Y192290I-583J-1385D01*
G03X513917Y192915I-309J255D01*
G02X513002Y194173I583J1385D01*
G03X512518Y194531I-399J-34D01*
G02X510991Y196893I-318J1469D01*
G02X513698Y196127I1209J-893D01*
G03X514182Y195769I399J34D01*
G02X515709Y193407I318J-1469D01*
G02X515660Y193344I-1211J891D01*
G03X515814Y192719I309J-255D01*
G37*
G36*
G01X608350Y178782D02*
Y185932D01*
X608393Y186204D01*
G02X615053Y185690I3309J-532D01*
G02X615054Y185656I-3348J-115D01*
G01Y178991D01*
G02X608380Y178555I-3352J5D01*
G01X608350Y178782D01*
G37*
G36*
G01X625472Y177097D02*
G02X623500Y177323I-1114J-1007D01*
G03X623648Y178839I-571J821D01*
G02X623606Y178884I1150J1116D01*
G02X623198Y179951I1194J1068D01*
G01Y185029D01*
X623201Y185073D01*
G02X626402Y184959I1599J-106D01*
G01Y184958D01*
Y184848D01*
X626404Y184845D01*
Y179891D01*
X626394Y179789D01*
X626391Y179763D01*
G02X625660Y178601I-1591J190D01*
G03X625472Y177097I554J-833D01*
G37*
G36*
G01X556923Y174381D02*
G02X555308Y175360I-1413J-509D01*
G03X556170Y176424I-135J991D01*
G02X556178Y176720I1498J108D01*
G03X555445Y177809I-993J123D01*
G02X557326Y179073I391J1450D01*
G03X558059Y177984I993J-123D01*
G02X559169Y176492I-391J-1450D01*
G03X559663Y175978I500J-14D01*
G02X558145Y174518I-17J-1502D01*
G03X557651Y175032I-500J14D01*
G02X557462Y175046I16J1502D01*
G03X556923Y174381I-69J-495D01*
G37*
G36*
G01X559956Y157686D02*
G02X559745Y159899I-1111J1011D01*
G03X561084Y160026I600J800D01*
G02X561459Y160324I1110J-1012D01*
G03X561890Y161585I-490J872D01*
G02X562142Y163157I1384J584D01*
G03X562197Y164404I-753J658D01*
G02X564542Y164301I1214J885D01*
G03X564487Y163054I753J-658D01*
G02X564010Y160860I-1213J-885D01*
G03X563579Y159599I490J-872D01*
G02X561295Y157813I-1384J-584D01*
G03X559956Y157686I-600J-800D01*
G37*
G36*
G01X548825Y142632D02*
G02X548615Y144467I-1282J783D01*
G03X550182Y144645I714J700D01*
G02X550392Y142810I1282J-783D01*
G03X548825Y142632I-714J-700D01*
G37*
G36*
G01X595439Y139632D02*
G02X593936Y138164I-1J-1502D01*
G03X592937Y139187I-1000J23D01*
G02X594440Y140655I1J1502D01*
G03X595439Y139632I1000J-23D01*
G37*
G36*
G01X519321Y138743D02*
G02X517313Y138867I-1073J-1051D01*
G03X517404Y140350I-623J783D01*
G02X519412Y140226I1073J1051D01*
G03X519321Y138743I623J-783D01*
G37*
G36*
G01X550748Y134091D02*
G02X549110Y132794I-149J-1495D01*
G03X548218Y133920I-991J131D01*
G02X549856Y135217I149J1495D01*
G03X550748Y134091I991J-131D01*
G37*
G36*
G01X510239Y124750D02*
G02X508052Y125300I-1335J-687D01*
G03X508375Y126582I-566J824D01*
G02X510562Y126032I1335J687D01*
G03X510239Y124750I566J-824D01*
G37*
G36*
G01X547933Y107918D02*
G02X545997Y107413I-685J-1336D01*
G03X545621Y108857I-833J554D01*
G02X547557Y109362I685J1336D01*
G03X547933Y107918I833J-554D01*
G37*
G36*
G01X542106Y107828D02*
G02X540747Y106284I142J-1495D01*
G03X539652Y107247I-1000J-33D01*
G02X541011Y108791I-142J1495D01*
G03X542106Y107828I1000J33D01*
G37*
G36*
G01X518181Y99465D02*
G02X515733Y99460I-1226J868D01*
G03X514134Y99498I-814J-582D01*
G02X514177Y101301I-1179J930D01*
G03X515776Y101263I814J582D01*
G02X518131Y101268I1179J-930D01*
G03X519729Y101312I782J622D01*
G02X519779Y99509I1226J-868D01*
G03X518181Y99465I-782J-622D01*
G37*
G36*
G01X506189Y98974D02*
G02X506122Y100775I-1234J856D01*
G03X507721Y100834I777J629D01*
G02X507788Y99033I1234J-856D01*
G03X506189Y98974I-777J-629D01*
G37*
G36*
G01X545967Y206672D02*
G02X543163Y206311I-1467J326D01*
G03X542565Y206447I-356J-184D01*
G02X541008Y209001I-907J1198D01*
G02X542860Y208547I650J-1355D01*
G02X542993Y208333I-1206J-898D01*
G03X543592Y208198I356J184D01*
G02X545967Y206672I908J-1198D01*
G37*
G36*
G01X714582Y678623D02*
G02X712587Y678874I-1137J-982D01*
G03X712773Y680348I-571J821D01*
G02X714768Y680097I1137J982D01*
G03X714582Y678623I571J-821D01*
G37*
G36*
G01X719411Y678791D02*
G02X717518Y678823I-966J-1150D01*
G03X717544Y680376I-617J787D01*
G02X719437Y680344I966J1150D01*
G03X719411Y678791I617J-787D01*
G37*
G36*
G01X677440Y779513D02*
G02X676257Y779935I-1050J-1074D01*
G01X676392Y779947D01*
X676569Y780539D01*
G03X676440Y781040I-479J144D01*
G02X678271Y783397I1050J1074D01*
G03X679739Y783936I519J855D01*
G02X680383Y782178I1425J-475D01*
G03X678915Y781639I-519J-855D01*
G02X677623Y780618I-1425J475D01*
G01X677488Y780606D01*
X677311Y780014D01*
G03X677440Y779513I479J-144D01*
G37*
G36*
G01X621853Y694435D02*
G02X619665Y695089I-1373J-608D01*
G03X620037Y696333I-543J840D01*
G02X622225Y695679I1373J608D01*
G03X621853Y694435I543J-840D01*
G37*
G36*
G01X588538Y688114D02*
G02X587018Y689720I-1498J104D01*
G03X588002Y690650I-14J1000D01*
G02X589522Y689044I1498J-104D01*
G03X588538Y688114I14J-1000D01*
G37*
G36*
G01X578012Y687826D02*
G02X575933Y689048I-1493J-161D01*
G03X576537Y690075I-390J921D01*
G02X578616Y688853I1493J161D01*
G03X578012Y687826I390J-921D01*
G37*
G36*
G01X699148Y711871D02*
G02X678806I-10171J-12068D01*
G03X679494Y713350I-1246J1479D01*
G01Y719488D01*
G02X698460I9483J0D01*
G01Y713350D01*
G03X699148Y711871I1934J0D01*
G37*
G36*
G01X641672Y683765D02*
G02X639125Y685335I-1343J673D01*
G03X638969Y686695I-802J597D01*
G02X641425Y688065I971J1146D01*
G03X642648Y687241I989J148D01*
G02X642739Y684302I352J-1460D01*
G03X641672Y683765I-173J-985D01*
G37*
G36*
G01X613055Y682890D02*
G02X611169Y681484I-385J-1452D01*
G03X610425Y682481I-1000J30D01*
G02X609615Y684843I385J1452D01*
G03X609550Y685519I-398J303D01*
G02X610468Y688140I1000J1121D01*
G03X611372Y688852I-54J999D01*
G02X611425Y689000I1438J-432D01*
G03X610865Y689683I-461J193D01*
G02X609668Y692357I-295J1473D01*
G03Y693955I-601J799D01*
G02X611472I902J1201D01*
G03Y692357I601J-799D01*
G02X612065Y691009I-902J-1201D01*
G03X612960Y689917I995J-97D01*
G02X612893Y686922I-148J-1495D01*
G03X611989Y686210I54J-999D01*
G02X611745Y685730I-1439J430D01*
G03X611810Y685054I398J-303D01*
G02X612311Y683887I-1000J-1120D01*
G03X613055Y682890I1000J-30D01*
G37*
G36*
G01X602715Y680487D02*
G02X600549Y679457I-695J-1331D01*
G03X600032Y680545I-980J201D01*
G02X602198Y681575I695J1331D01*
G03X602715Y680487I980J-201D01*
G37*
G36*
G01X577832Y677118D02*
G02X575738Y677000I-986J-1133D01*
G03X575658Y678429I-737J675D01*
G02X575601Y680643I986J1133D01*
G03X575747Y681904I-694J719D01*
G02X578053Y681637I1263J814D01*
G03X577907Y680376I694J-719D01*
G02X577752Y678547I-1263J-814D01*
G03X577832Y677118I737J-675D01*
G37*
G36*
G01X565360Y676104D02*
G02X563680Y674818I-192J-1490D01*
G03X563249Y675382I-495J68D01*
G02X562991Y678305I192J1490D01*
G03X563681Y679401I-300J954D01*
G02X563670Y679730I1487J214D01*
G03X563038Y680738I-997J77D01*
G02X563036Y683535I548J1399D01*
G03X563669Y684525I-365J931D01*
G02X563667Y684554I1497J118D01*
G03X562958Y685470I-999J-41D01*
G02X562968Y688349I435J1438D01*
G03X563677Y689430I-283J959D01*
G02X563679Y689813I1491J184D01*
G03X563043Y690880I-991J132D01*
G02X563294Y693759I534J1404D01*
G03X563691Y694341I-95J491D01*
G02X565451Y693139I1477J273D01*
G03X565054Y692557I95J-491D01*
G02X565066Y692085I-1477J-274D01*
G03X565702Y691018I991J-132D01*
G02X565593Y688173I-534J-1404D01*
G03X564884Y687092I283J-959D01*
G02X564894Y686968I-1491J-183D01*
G03X565603Y686052I999J41D01*
G02X565718Y683216I-435J-1438D01*
G03X565085Y682226I365J-931D01*
G02X565084Y682021I-1499J-95D01*
G03X565716Y681013I997J-77D01*
G02X565618Y678181I-548J-1399D01*
G03X564928Y677085I300J-954D01*
G02X564929Y676668I-1487J-212D01*
G03X565360Y676104I495J-68D01*
G37*
G36*
G01X518576Y671392D02*
G02X516686Y671102I-769J-1290D01*
G03X516452Y672627I-746J666D01*
G02X518342Y672917I769J1290D01*
G03X518576Y671392I746J-666D01*
G37*
G36*
G01X709217Y671025D02*
G02X707120Y670582I-831J-1251D01*
G03X706829Y671953I-843J537D01*
G02X708926Y672396I831J1251D01*
G03X709217Y671025I843J-537D01*
G37*
G36*
G01X704577Y670689D02*
G02X702305Y670817I-1191J-915D01*
G03X702379Y672121I-719J695D01*
G02X704651Y671993I1191J915D01*
G03X704577Y670689I719J-695D01*
G37*
G36*
G01X481805Y669350D02*
G02X481367Y667109I739J-1308D01*
G03X480092Y667358I-783J-622D01*
G02X480530Y669599I-739J1308D01*
G03X481805Y669350I783J622D01*
G37*
G36*
G01X694276Y668451D02*
G02X692097Y668011I-890J-1210D01*
G03X691830Y669330I-859J513D01*
G02X694009Y669770I890J1210D01*
G03X694276Y668451I859J-513D01*
G37*
G36*
G01X699601Y668124D02*
G02X697438Y668406I-1215J-883D01*
G03X697615Y669769I-632J775D01*
G02X699778Y669487I1215J883D01*
G03X699601Y668124I632J-775D01*
G37*
G36*
G01X680997Y668140D02*
G02X679868Y666252I313J-1469D01*
G03X678699Y666951I-960J-279D01*
G02X679828Y668839I-313J1469D01*
G03X680997Y668140I960J279D01*
G37*
G36*
G01X672902Y666172D02*
G02X671094Y667622I-1502J-21D01*
G03X671888Y668528I-203J979D01*
G02X673564Y666929I1498J-108D01*
G03X673248Y666761I61J-496D01*
G01X673026Y666508D01*
G03X672902Y666172I376J-330D01*
G37*
G36*
G01X491621Y662637D02*
G02X490210Y664202I-1501J66D01*
G03X491269Y665156I60J998D01*
G02X492680Y663591I1501J-66D01*
G03X491621Y662637I-60J-998D01*
G37*
G36*
G01X592537Y657044D02*
G02X589950Y655523I-1258J-820D01*
G03X588416Y655816I-884J-467D01*
G02X588769Y657658I-976J1142D01*
G03X590303Y657365I884J467D01*
G02X590358Y657410I979J-1140D01*
G03X590582Y658747I-613J790D01*
G02X592761Y658381I1258J821D01*
G03X592537Y657044I613J-790D01*
G37*
G36*
G01X614451Y656071D02*
G02X613619Y657486I-1501J69D01*
G03X614199Y657826I179J359D01*
G02X615031Y656411I1501J-69D01*
G03X614451Y656071I-179J-359D01*
G37*
G36*
G01X596231Y653281D02*
G02X594538Y654874I-1498J104D01*
G03X594972Y655335I-65J496D01*
G02X595623Y656471I1498J-104D01*
G03X595755Y657165I-282J413D01*
G02X597845Y656768I1243J843D01*
G03X597713Y656074I282J-413D01*
G02X596665Y653742I-1243J-843D01*
G03X596231Y653281I65J-496D01*
G37*
G36*
G01X546559Y646667D02*
G02Y648521I-1182J927D01*
G03X548132I786J617D01*
G02Y646667I1182J-927D01*
G03X546559I-786J-617D01*
G37*
G36*
G01X615327Y646374D02*
G02X613361Y645951I-748J-1302D01*
G03X613048Y647403I-811J585D01*
G02X615014Y647826I748J1302D01*
G03X615327Y646374I811J-585D01*
G37*
G36*
G01X492601Y644301D02*
G02X490751Y645812I-1501J50D01*
G03X491519Y646751I-231J973D01*
G02X493369Y645240I1501J-50D01*
G03X492601Y644301I231J-973D01*
G37*
G36*
G01X507268Y642749D02*
G02X505662Y644040I-1488J-206D01*
G03X506573Y645175I-79J997D01*
G02X508179Y643884I1488J206D01*
G03X507268Y642749I79J-997D01*
G37*
G36*
G01X606058Y640359D02*
G02X605943Y642612I-1048J1076D01*
G03X607262Y642679I621J784D01*
G02X607377Y640426I1048J-1076D01*
G03X606058Y640359I-621J-784D01*
G37*
G36*
G01X621956Y639019D02*
G02X620733Y640912I-1446J408D01*
G03X621844Y641630I148J989D01*
G02X623067Y639737I1446J-408D01*
G03X621956Y639019I-148J-989D01*
G37*
G36*
G01X666369Y614641D02*
G02X665016Y616038I-1499J-98D01*
G03X666111Y617099I97J995D01*
G02X667464Y615702I1499J98D01*
G03X666369Y614641I-97J-995D01*
G37*
G36*
G01X498874Y586851D02*
G03X499142Y587970I-661J750D01*
G02X501532Y587399I1396J555D01*
G03X501264Y586280I661J-750D01*
G02X498874Y586851I-1396J-555D01*
G37*
G36*
G01X513321Y589675D02*
G02X513224Y592050I-967J1150D01*
G03X514446Y592100I579J815D01*
G02X514543Y589725I967J-1150D01*
G03X513321Y589675I-579J-815D01*
G37*
G36*
G01X552594Y569593D02*
G02X550302Y569378I-1056J-1068D01*
G03X550182Y570657I-823J568D01*
G02X552474Y570872I1056J1068D01*
G03X552594Y569593I823J-568D01*
G37*
G36*
G01X552133Y548293D02*
G02X550295Y548375I-972J-1145D01*
G03X550366Y549955I-576J817D01*
G02X552204Y549873I972J1145D01*
G03X552133Y548293I576J-817D01*
G37*
G36*
G01X577116Y543602D02*
G02X574838Y543021I-908J-1197D01*
G03X574530Y544228I-912J410D01*
G02X574501Y546599I908J1197D01*
G03X574661Y548002I-624J782D01*
G02X574512Y549640I1177J933D01*
G03X574272Y550875I-883J469D01*
G02X574059Y552956I966J1150D01*
G03X574009Y553630I-392J310D01*
G02X575269Y556209I1029J1095D01*
G03X576364Y556861I153J988D01*
G02X577547Y554871I1414J-506D01*
G03X576452Y554219I-153J-988D01*
G02X576217Y553794I-1415J505D01*
G03X576267Y553120I392J-310D01*
G02X576564Y551320I-1029J-1094D01*
G03X576804Y550085I883J-469D01*
G02X576775Y547761I-966J-1150D01*
G03X576615Y546358I624J-782D01*
G02X576808Y544809I-1177J-933D01*
G03X577116Y543602I912J-410D01*
G37*
G36*
G01X622884Y591342D02*
X622090Y592135D01*
Y613700D01*
X622884Y614494D01*
X644490D01*
X645448Y613535D01*
Y592259D01*
X644531Y591342D01*
X622884D01*
G37*
G36*
G01X687479Y620063D02*
G03X686308Y620046I-574J-819D01*
G02X686271Y622481I-898J1204D01*
G03X687442Y622498I574J819D01*
G02X687479Y620063I898J-1204D01*
G37*
G36*
G01X714208Y621333D02*
G02X714152Y619292I1074J-1051D01*
G03X712686Y619332I-752J-659D01*
G02X712742Y621373I-1074J1051D01*
G03X714208Y621333I752J659D01*
G37*
G36*
G01X657040Y608573D02*
G02X656718Y610942I-1062J1062D01*
G03X657918Y611105I493J870D01*
G02X658240Y608736I1062J-1062D01*
G03X657040Y608573I-493J-870D01*
G37*
G54D23*
X33841Y9183D03*
X28104Y30414D03*
X36848Y25198D03*
X28408Y26414D03*
X34149Y44149D03*
X30282Y34564D03*
X36588Y32278D03*
X36567Y73145D03*
X39126Y84631D03*
X34008Y91017D03*
X36567Y107988D03*
X32260Y96899D03*
X44010Y55170D03*
X54981Y59420D03*
X41685Y73110D03*
X51340Y69181D03*
X46570Y73891D03*
X47510Y109421D03*
X54703Y122796D03*
X60318Y65593D03*
X61760Y107321D03*
X55230Y112521D03*
X85951Y410263D03*
X101449Y194368D03*
X101020Y223348D03*
X95951Y376661D03*
X112530Y186363D03*
X106760Y175370D03*
X114920Y179082D03*
X108910Y193194D03*
X106517Y210796D03*
X103151Y373340D03*
X110490Y397362D03*
X107531Y394023D03*
X135050Y53493D03*
X137540Y58255D03*
X157010Y58963D03*
X161577Y436834D03*
X161563Y432521D03*
X154370Y449930D03*
X165336Y46126D03*
X178217Y435317D03*
X170683Y436834D03*
X182879Y435312D03*
X221406Y436560D03*
X240599Y440053D03*
X89810Y765905D03*
X18960Y572061D03*
X17876Y578422D03*
X16200Y566921D03*
X21881Y595792D03*
X14500Y601957D03*
X11980Y617956D03*
X14550Y628297D03*
X13807Y634826D03*
X17071Y658951D03*
X23610Y568111D03*
X34440Y597285D03*
X28112Y591718D03*
X36930Y611082D03*
X28270Y602194D03*
X33140Y602232D03*
X28185Y612088D03*
X35862Y617052D03*
X30744Y617898D03*
X29964Y658951D03*
X24168Y655750D03*
X37920Y651828D03*
X49680Y579709D03*
X47557Y588971D03*
X44507Y594082D03*
X40908Y589691D03*
X43850Y602797D03*
X42950Y612487D03*
X52230Y614907D03*
X47480Y616848D03*
X50170Y636895D03*
X51038Y643928D03*
X46890Y633564D03*
X53751Y652029D03*
X44640Y651029D03*
X40980Y656396D03*
X63570Y613914D03*
X61600Y653611D03*
X66880Y761625D03*
X80630Y689682D03*
X82847Y716068D03*
X98410Y680541D03*
X100223Y733207D03*
X115748Y716275D03*
X149860Y726626D03*
X180820Y717914D03*
X175463Y720245D03*
X177920Y739302D03*
X150547Y459363D03*
X109640Y611890D03*
X109410Y621425D03*
X109500Y616724D03*
X109260Y644687D03*
Y648989D03*
X157963Y633735D03*
X162530Y636435D03*
X179532Y600437D03*
X173432D03*
X165832Y600337D03*
Y606037D03*
Y613137D03*
X172532Y619537D03*
X178632Y619437D03*
X165832D03*
X179120Y639615D03*
X169930Y635329D03*
X172510Y639771D03*
X174479Y631986D03*
X185032Y606737D03*
X184932Y600537D03*
X185032Y612937D03*
X184932Y619437D03*
X192130Y632235D03*
X184748Y639687D03*
X191480Y639135D03*
X200380Y629085D03*
X199786Y618893D03*
X197230Y615435D03*
X197130Y626135D03*
X197480Y639815D03*
X135507Y421367D03*
X175993Y414924D03*
X167527Y420268D03*
X190700Y418325D03*
X201267Y403294D03*
X224730Y418003D03*
X262798Y417886D03*
X265532Y422648D03*
X160040Y108844D03*
X190100Y99701D03*
X188203Y104567D03*
X186730Y121202D03*
X202560Y107797D03*
X210203Y108457D03*
X199993Y103637D03*
X210623Y121267D03*
X207070Y179744D03*
X207154Y175212D03*
X207041Y184502D03*
X207070Y188978D03*
X226713Y122007D03*
X228138Y125802D03*
X226010Y233542D03*
X217135Y230585D03*
X226010Y240342D03*
X233268Y121742D03*
X233138Y125802D03*
X232948Y234047D03*
X236710Y244042D03*
X242460Y237591D03*
X252683Y105867D03*
X256133Y99347D03*
X249453Y114307D03*
X255287Y226709D03*
X256492Y222466D03*
X257950Y236924D03*
X254418Y240407D03*
X262473Y106937D03*
X269010Y121648D03*
X264980Y121886D03*
X260108Y240376D03*
X269263Y252800D03*
X287595Y106109D03*
X290154Y244007D03*
X279161Y237817D03*
X283660Y251542D03*
X281954Y255588D03*
X276904Y252550D03*
X293873Y130357D03*
X302930Y132994D03*
X327430Y108208D03*
X332453Y122297D03*
X331583Y128717D03*
X177680Y101764D03*
X180990Y108770D03*
X206144Y252477D03*
X188442Y252643D03*
X167951Y380551D03*
X168058Y376035D03*
X168110Y350642D03*
X167383Y341306D03*
X166189Y335285D03*
X178941Y270160D03*
X170510Y275522D03*
X170617Y267326D03*
X167698Y260617D03*
X167322Y255855D03*
X171668Y256287D03*
X177891Y249324D03*
X165290Y385948D03*
X160058Y375818D03*
X164418Y348187D03*
X150510Y336306D03*
X150918Y318134D03*
X151230Y330164D03*
X161513Y317143D03*
X158076Y290635D03*
X152733Y288517D03*
X149721Y292987D03*
X161918Y293869D03*
X152634Y276809D03*
X162484Y276599D03*
X154546Y256986D03*
X160449Y259605D03*
X161918Y254287D03*
X157690Y249918D03*
X152990Y248096D03*
X162317Y249877D03*
X144058Y376025D03*
X136506Y332193D03*
X145580Y316836D03*
X146100Y323543D03*
X135224D03*
X134768Y319043D03*
X135730Y314543D03*
X145720Y311336D03*
X149020Y303498D03*
X134540Y267786D03*
X148350Y281769D03*
X138930Y278965D03*
X145200Y276468D03*
X141682Y269829D03*
X143150Y281123D03*
X148330Y258806D03*
X195126Y249955D03*
X534638Y539825D03*
X513838Y556925D03*
X510338Y571325D03*
X487398Y576665D03*
X490661Y547148D03*
X468740Y585897D03*
X455890Y592792D03*
X460236Y581679D03*
X437516Y587579D03*
X424904Y586283D03*
X341011Y537828D03*
X340330Y541931D03*
X340182Y531787D03*
X341512Y512429D03*
X340902Y503742D03*
X336010Y531598D03*
X335860Y516486D03*
X329672Y502057D03*
X335162Y502791D03*
X330115Y490303D03*
X326740Y495763D03*
X325040Y480129D03*
X315980Y472128D03*
X321246Y472669D03*
X316956Y478833D03*
X269109Y472353D03*
X264909Y472553D03*
X260609Y472453D03*
X251309Y472553D03*
X246109Y472465D03*
X255509Y472253D03*
X228604Y479682D03*
X234209Y480953D03*
X241909Y472553D03*
X237609Y472453D03*
X233309Y472553D03*
X226255Y472579D03*
X212342Y536729D03*
X200434Y478345D03*
X193466Y546886D03*
X185747Y487664D03*
X169728D03*
X164259Y557273D03*
X149477Y532733D03*
X124279Y523691D03*
X122018Y516353D03*
X183698Y285693D03*
X193557Y294428D03*
X187812Y286352D03*
X192298Y286183D03*
X202525Y299358D03*
X225199Y281098D03*
X224357Y273228D03*
X225199Y287398D03*
X222049Y290548D03*
X215749Y287398D03*
X237799Y290548D03*
Y284248D03*
X231499Y287398D03*
Y309448D03*
X257046Y279607D03*
X244109Y277996D03*
X250399Y296848D03*
X253611Y293765D03*
X250399Y290548D03*
X244099Y284248D03*
X250399D03*
X244099Y293698D03*
X244118Y309387D03*
X286010Y276042D03*
X290363Y286082D03*
X286132Y285953D03*
X281818Y290787D03*
X295307Y275439D03*
X336495Y290569D03*
X342955Y291523D03*
X354580Y298101D03*
X369934Y322946D03*
X384248Y319157D03*
X372080Y330574D03*
X399880Y319568D03*
X390080Y331575D03*
X404738Y260421D03*
X428405Y245194D03*
X422178Y266891D03*
X426335Y267062D03*
X418597Y273538D03*
X426948Y281051D03*
X428748Y275222D03*
X423178Y284601D03*
X427909Y286759D03*
X427468Y292287D03*
X418718Y301181D03*
X441580Y250730D03*
X441792Y259473D03*
X442148Y279361D03*
X442165Y271284D03*
X441076Y294906D03*
X445540Y288853D03*
X445890Y283317D03*
X441361Y300812D03*
X454150Y249053D03*
X457165Y262368D03*
X449290Y276227D03*
X449860Y272121D03*
X452900Y281647D03*
X451790Y300129D03*
X464810Y311253D03*
X511070Y310719D03*
X526250Y310940D03*
X518590Y310129D03*
X519650Y320384D03*
X522420Y315475D03*
X517260Y315978D03*
X523930Y321642D03*
X528680Y317349D03*
X541380Y340358D03*
X543110Y333848D03*
X553690Y340829D03*
X547340Y339103D03*
X579788Y354743D03*
X619014Y408353D03*
X621399Y420400D03*
X627022Y383713D03*
X652139Y377125D03*
X647440Y386383D03*
X641236Y381616D03*
X645236Y377858D03*
X647340Y393283D03*
X647440Y408383D03*
X647340Y400083D03*
X662390Y377039D03*
X654340Y386283D03*
X661140D03*
X669215Y377488D03*
X654840Y408483D03*
X661940Y408383D03*
X669540Y386283D03*
X674235Y379364D03*
X669440Y395183D03*
Y408483D03*
X669540Y402783D03*
X673368Y416621D03*
X276687Y385100D03*
X264421Y384812D03*
X260536Y374216D03*
X244595Y363535D03*
X256588Y359005D03*
X251491Y357134D03*
X246265Y355855D03*
X251334Y352857D03*
X232647Y396011D03*
X236430Y393470D03*
X243078Y368384D03*
X233136Y367070D03*
X237578Y369584D03*
X230010Y373300D03*
X238084Y355992D03*
X240692Y344204D03*
X214406Y395539D03*
X200488Y396425D03*
X200439Y390168D03*
X202823Y376922D03*
X194330Y396425D03*
X185074Y380726D03*
X193590Y383383D03*
X192681Y377554D03*
X194231Y390267D03*
X184058Y376479D03*
X180440Y398056D03*
X180430Y392969D03*
X261539Y387755D03*
X305708Y503043D03*
X296913Y514460D03*
X301457Y513837D03*
X318968Y536052D03*
X277475Y695723D03*
X275710Y681593D03*
X278350Y687309D03*
X269420Y677062D03*
X267240Y682519D03*
X270140Y691038D03*
X261890Y664761D03*
X253398Y692357D03*
X252486Y671772D03*
X257271D03*
X249462Y648383D03*
X239168Y671672D03*
X243596Y671772D03*
X241670Y652558D03*
X234500Y637685D03*
X238420Y642148D03*
X244780Y682521D03*
X237275Y679609D03*
X268502Y344181D03*
X285704Y321809D03*
X275602Y343811D03*
X278943Y346914D03*
X277718Y352687D03*
X283140Y346082D03*
X279863Y367513D03*
X286550Y374402D03*
X303759Y331478D03*
X295527Y359812D03*
X303171Y374224D03*
X322765Y327721D03*
X309131Y374573D03*
X313222Y374229D03*
X336850Y380332D03*
X366140Y407639D03*
X360350Y395873D03*
X319135Y591407D03*
X315957Y594127D03*
X342759Y599193D03*
X353298Y633903D03*
X363530Y629727D03*
X385573Y629998D03*
X373218Y634217D03*
X382580Y637413D03*
X413930Y639810D03*
X406100Y631851D03*
X320512Y613603D03*
X308741Y623871D03*
X311311Y618197D03*
X317492Y618193D03*
X323346Y621930D03*
X329110Y623514D03*
X295950Y689520D03*
X297300Y697221D03*
X305990Y697189D03*
X313230Y702465D03*
X355150Y486758D03*
X368943Y506356D03*
X381760Y496004D03*
X374203Y491029D03*
X389107Y492097D03*
X388982Y496939D03*
X521320Y178184D03*
X526875Y161838D03*
X519183Y224173D03*
X551395Y174172D03*
X547927Y212190D03*
X549909Y207060D03*
X611848Y359784D03*
X600770Y358702D03*
X646013Y358110D03*
X618581Y354818D03*
X607855Y352341D03*
X639838Y349818D03*
X628141Y344818D03*
X607671D03*
X640647Y339854D03*
X648450Y338711D03*
X630190Y336986D03*
X625190D03*
X619190D03*
X613640D03*
X598551Y329541D03*
X609150Y328514D03*
X627000Y327926D03*
X616490Y327534D03*
X633470Y326710D03*
X601450Y326509D03*
X622890Y325227D03*
X590984Y323246D03*
X631860Y321455D03*
X623820Y321062D03*
X591977Y319360D03*
X628140Y317610D03*
X592201Y308988D03*
X585584Y308881D03*
X593607Y305034D03*
X588607D03*
X565953Y301635D03*
X631672Y301066D03*
X561525Y298192D03*
X649995Y296433D03*
X566876Y289890D03*
X555072Y289563D03*
X634212Y281670D03*
X557207Y280328D03*
X564274Y279395D03*
X604926Y278476D03*
X545223Y276895D03*
X596574Y276393D03*
X590874Y275195D03*
X566774D03*
X581474Y274795D03*
X612974Y269095D03*
X525480Y268959D03*
X539267Y267102D03*
X545116Y266847D03*
X529527Y265584D03*
X622470Y261628D03*
X578076Y260093D03*
X571476D03*
X564676D03*
X547929Y258102D03*
X594174Y256695D03*
X504160Y255584D03*
X515675Y254098D03*
X564676Y253693D03*
X578076Y253393D03*
X596774Y249795D03*
X517670Y247527D03*
X550090Y247079D03*
X578076Y246693D03*
X571576D03*
X564676D03*
X545703Y245725D03*
X488816Y242877D03*
X617778Y238873D03*
X536676Y234993D03*
X576105Y231626D03*
X528105Y230594D03*
X591707Y230162D03*
X585579Y230095D03*
X579707Y229395D03*
X534208Y227832D03*
X545424Y226722D03*
X568410Y226647D03*
X572690Y226569D03*
X572020Y222393D03*
X567980Y222353D03*
X595707Y220995D03*
X579707Y220662D03*
X547148Y220220D03*
X516551Y214987D03*
X487168Y214568D03*
X524405Y212531D03*
X585580Y210516D03*
X486738Y210434D03*
X506234Y207368D03*
X520068Y207142D03*
X450650Y203785D03*
X523593Y198171D03*
X468452Y197934D03*
X452115Y195057D03*
X520015Y194584D03*
X582920Y194220D03*
X588692Y192809D03*
X505580Y192555D03*
X558768Y191223D03*
X624950Y189801D03*
X486370Y189279D03*
X581915Y179955D03*
X563129Y178369D03*
X592491Y175906D03*
X592917Y171906D03*
X550604Y168072D03*
X582792Y167632D03*
X490130Y163086D03*
X579897Y161355D03*
X593537Y161023D03*
X584438Y160933D03*
X550370Y157461D03*
X581565Y154969D03*
X558059Y154254D03*
X613432Y153528D03*
X527349Y152246D03*
X550550Y151682D03*
X538655Y151415D03*
X527898Y147146D03*
X502132Y146686D03*
X564076Y145372D03*
X558348Y142511D03*
X548007Y139415D03*
X587968Y138765D03*
X552173Y138528D03*
X592938Y133232D03*
X594938Y127893D03*
X518640Y125539D03*
X605070Y123991D03*
X594920Y123370D03*
X583661Y121836D03*
X583829Y117732D03*
X592938Y117657D03*
X617925Y114064D03*
X550490Y112989D03*
X542700Y112881D03*
X535960Y112850D03*
X600118Y112568D03*
X557995Y110244D03*
X566090Y109136D03*
X618623Y108918D03*
X610543Y107678D03*
X578938Y103123D03*
X569559D03*
X532955Y100604D03*
X536955Y100257D03*
X500955Y100139D03*
X488438Y100123D03*
X496955Y99958D03*
X528955Y99781D03*
X524955Y99359D03*
X555938Y97292D03*
X560938Y97195D03*
X565938Y96820D03*
X547480Y96632D03*
X542180Y93534D03*
X536232Y192086D03*
X499154Y194198D03*
X491046Y207506D03*
X487839Y194142D03*
X488017Y203716D03*
X498867Y227773D03*
X498875Y217172D03*
X681480Y777388D03*
X677227Y786454D03*
X688510Y735294D03*
X705870Y721832D03*
X672630Y720752D03*
X655610Y706309D03*
X656505Y701191D03*
X607380Y699671D03*
X708450Y695489D03*
X669390Y695406D03*
X600690Y691896D03*
X657340Y690286D03*
X617235Y689036D03*
X663040Y688057D03*
X600727Y686876D03*
X527111Y686052D03*
X506470Y683512D03*
X634251Y683493D03*
X656254Y683277D03*
X586060Y682582D03*
X689100Y680291D03*
X533270Y679351D03*
X526600Y679117D03*
X505580Y679105D03*
X518382Y678247D03*
X668000Y676595D03*
X501914Y675624D03*
X610651Y675156D03*
X600719D03*
X539734Y675020D03*
X482398Y673087D03*
X614909Y671938D03*
X496453Y670876D03*
X504114Y670830D03*
X551283Y670800D03*
X620160Y670594D03*
X565168Y669614D03*
X529525Y669349D03*
X539830Y667332D03*
X615940Y666862D03*
X659978Y666274D03*
X504241Y665809D03*
X518800Y665776D03*
X497320Y665216D03*
X526430Y664730D03*
X565168Y664614D03*
X613200Y661577D03*
X529899Y661020D03*
X656971Y660492D03*
X484700Y660355D03*
X495622Y660178D03*
X631930Y655254D03*
X542424Y654821D03*
X646580Y654775D03*
X551230Y652844D03*
X521516Y650576D03*
X515438Y649996D03*
X647870Y649784D03*
X479512Y649436D03*
X535230Y648711D03*
X501940Y644073D03*
X646940Y643448D03*
X600980Y641533D03*
X655170Y639432D03*
X650928Y639290D03*
X638470D03*
X627146Y638932D03*
X622510Y635544D03*
X616730Y633290D03*
X654221Y631425D03*
X641263Y631393D03*
X634137Y631342D03*
X611572Y629894D03*
X649173Y629876D03*
X623940Y628720D03*
X636890Y627095D03*
X654645Y627064D03*
X663560Y625019D03*
X659600Y623785D03*
X533038Y590325D03*
X540701Y590162D03*
X527638Y590325D03*
X551438Y561225D03*
X550938Y587325D03*
X547000Y590163D03*
X566298Y548465D03*
X566338Y554235D03*
X561174Y564471D03*
X565858Y576195D03*
X561198Y581793D03*
X566378Y567725D03*
X561608Y571775D03*
X565398Y584765D03*
X561568Y589355D03*
X575138Y559825D03*
X575038Y567725D03*
X611254Y617943D03*
X634921Y580163D03*
X651437Y578943D03*
X665170Y595943D03*
X661396Y588900D03*
X664603Y601976D03*
X695600Y590788D03*
X713300Y578995D03*
X713190Y583032D03*
X712740Y593101D03*
X720052Y620480D03*
G54D28*
X119900Y754021D03*
X125600Y759000D03*
X97390Y766435D03*
X104300Y773100D03*
X510000Y173500D03*
X516100Y178100D03*
X512600Y178900D03*
X515600Y172800D03*
X542002Y180100D03*
X546000Y180000D03*
X516625Y230075D03*
X533474Y196500D03*
X635000Y265400D03*
X519300Y220500D03*
X544700Y216100D03*
X526657Y207363D03*
X466200Y207300D03*
X512200Y204200D03*
X476400Y203100D03*
X471300Y201900D03*
X509100Y191900D03*
X546000Y192000D03*
X539500Y196500D03*
X544500Y197500D03*
X495300Y201600D03*
X496123Y233500D03*
X504941Y227859D03*
X499075Y235575D03*
X492700Y223800D03*
X704000Y770800D03*
X699600Y776000D03*
X689700Y774500D03*
X709500Y736800D03*
X706575Y740425D03*
G54D35*
X605796Y204845D03*
Y189845D03*
Y174845D03*
G54D24*
X83740Y20708D03*
X78740Y30708D03*
X73740Y20708D03*
G54D30*
X223376Y523322D03*
X186841Y545372D03*
X167105Y552882D03*
X173163Y551903D03*
X169157Y548676D03*
X174930Y547106D03*
X166297Y532416D03*
X172087Y510536D03*
X165707Y506156D03*
X173252Y515693D03*
X168189Y514331D03*
X159185Y537654D03*
X162335Y512456D03*
G54D29*
X247877Y105799D03*
G54D32*
X174105Y542290D03*
X178085Y518755D03*
X159196Y515612D03*
G54D34*
X609733Y215672D03*
X605796Y165160D03*
G54D31*
X188383Y556895D03*
X181232Y543953D03*
Y528205D03*
X184920Y508626D03*
X186467Y514036D03*
X186417Y518526D03*
X154900Y551832D03*
X154517Y513931D03*
X154307Y507507D03*
X243075Y508891D03*
X290323Y502595D03*
X277725Y527792D03*
G54D26*
X45282Y338300D03*
Y321764D03*
G54D25*
X76880Y143269D03*
X86880D03*
G54D33*
X434102Y311875D03*
G54D27*
X25455Y356832D03*
G54D22*
X102362Y349606D03*
%LPD*%
G75*
G36*
G01X166291Y98813D02*
G03I-594J0D01*
G37*
G36*
G01X172551Y105083D02*
G03I-594J0D01*
G37*
G36*
G01X217641Y103099D02*
G03I-594J0D01*
G37*
G36*
G01X232511Y105709D02*
G03I-594J0D01*
G37*
G36*
G01X248471Y105799D02*
G03I-594J0D01*
G37*
G36*
G01X328850Y342166D02*
X336310D01*
X336690Y341786D01*
Y325056D01*
X336420Y324786D01*
X328680D01*
X328260Y325206D01*
Y341576D01*
X328850Y342166D01*
G37*
G36*
G01X623092Y613285D02*
X623299Y613492D01*
X644075D01*
X644447Y613120D01*
Y592674D01*
X644116Y592343D01*
X623299D01*
X623092Y592550D01*
Y613285D01*
G37*
G54D10*
G01X4390Y533777D02*
Y288054D01*
X6272Y286172D01*
X50140D01*
X52330Y283982D01*
Y273354D01*
X58340Y267344D01*
Y254313D01*
X52260Y248233D01*
Y160852D01*
X57690Y155422D01*
Y147102D01*
X62910Y141882D01*
X64309D01*
G01X164812Y662579D02*
X164369Y662136D01*
X157380D01*
X152756Y657512D01*
X130472D01*
X125638Y662346D01*
X90141D01*
X80980Y653185D01*
Y600369D01*
X48851Y568240D01*
X41589D01*
X27650Y554301D01*
Y547155D01*
X23700Y543205D01*
Y541626D01*
X20975Y538901D01*
Y374096D01*
G01D02*
X21160Y373911D01*
Y369361D01*
X21530Y368991D01*
G01X169531Y710542D02*
X164331Y705342D01*
Y699626D01*
X157985Y693280D01*
X140188D01*
X133607Y686699D01*
G01X249013Y628514D02*
X242761D01*
X240485Y626238D01*
X225052D01*
X221490Y629800D01*
Y636639D01*
X216080Y642049D01*
Y654066D01*
X203830Y666316D01*
X173720D01*
X172991Y665587D01*
X156571D01*
X154400Y663416D01*
X151444D01*
X148140Y660112D01*
G01X206299Y306298D02*
X199384D01*
X198735Y305649D01*
X170014D01*
X169140Y306523D01*
X156825D01*
X154581Y308767D01*
G01X203166Y312577D02*
X203145Y312598D01*
X202115D01*
X200160Y314553D01*
Y317255D01*
X197498Y319917D01*
X195197D01*
X190557Y324557D01*
Y325701D01*
G01X231567Y321742D02*
X229399Y319574D01*
X221056D01*
X209840Y308358D01*
Y306444D01*
X206544Y303148D01*
X206299D01*
G01X205790Y387003D02*
X210948Y381845D01*
X214969D01*
X216633Y383509D01*
Y384989D01*
G01D02*
X219133Y382489D01*
X225991D01*
X228729Y385227D01*
G01X254007Y306819D02*
Y310915D01*
X257514Y314422D01*
X291545D01*
X293215Y316092D01*
X326310D01*
X329400Y313002D01*
X334828D01*
X337293Y315467D01*
Y316660D01*
G01X247789Y322910D02*
Y322903D01*
X250599Y320093D01*
X253384D01*
X256393Y317084D01*
X289412D01*
X291291Y318963D01*
X330751D01*
X331514Y319726D01*
X340270D01*
X344720Y324176D01*
Y325739D01*
G01X254560Y438829D02*
X256070Y437319D01*
G01D02*
X287160D01*
X291098Y433381D01*
Y400848D01*
X289683Y399433D01*
X282250D01*
X280487Y397670D01*
X271300D01*
X267993Y394363D01*
Y390695D01*
G01X340792Y307107D02*
X332393D01*
X330752Y305466D01*
X310389D01*
X308953Y306902D01*
X301327D01*
X295505Y312724D01*
X293560D01*
X286653Y305817D01*
X281342D01*
X280388Y306771D01*
X261939D01*
X260045Y308665D01*
Y309615D01*
G01X306294Y667156D02*
X312056D01*
X327130Y682230D01*
X335910D01*
X337325Y683645D01*
X348148D01*
X353260Y688757D01*
G01X341910Y325739D02*
X344720D01*
G01X392076Y470970D02*
X397790Y476684D01*
Y498506D01*
X388570Y507726D01*
Y562436D01*
X385410Y565596D01*
Y566122D01*
G01X443850Y634754D02*
X443359D01*
X439713Y638400D01*
X432614D01*
X427190Y643824D01*
Y648531D01*
X432640Y653981D01*
Y677390D01*
X433373Y678123D01*
Y685572D01*
X431909Y687036D01*
X430933D01*
X430813Y687156D01*
G01X668627Y527718D02*
X668823Y527914D01*
Y532470D01*
G01D02*
X695132D01*
X701170Y538508D01*
X4390Y533777D03*
X13170Y372673D03*
X18340Y366452D03*
X13120Y375871D03*
X16010Y369168D03*
X21530Y368991D03*
X14140Y391826D03*
X18210Y386530D03*
X13950Y388616D03*
X13390Y397543D03*
X14240Y394866D03*
X11680Y656335D03*
X9260Y658321D03*
X14000Y658369D03*
X14170Y653991D03*
X9360Y653943D03*
X30274Y37714D03*
X38280Y362184D03*
X35750Y364593D03*
X33420Y367309D03*
X23860Y366275D03*
X28250Y438740D03*
X37990Y453022D03*
X28250Y472076D03*
X37990Y520218D03*
X38807Y543539D03*
X51580Y17595D03*
X42205Y21518D03*
X54800Y25547D03*
X49244Y360352D03*
X40690Y359555D03*
X51670Y462885D03*
X47590Y463876D03*
X49830Y465496D03*
X47200Y467262D03*
X49590Y469432D03*
X49185Y472713D03*
X49720Y668412D03*
X56610Y20553D03*
X64309Y141882D03*
X68756Y167695D03*
X68930Y197193D03*
X57624Y366105D03*
X66262Y553344D03*
X68630Y599945D03*
X59260Y779815D03*
X58840Y783097D03*
X62290Y779629D03*
X67660Y779452D03*
X62730Y782694D03*
X66860Y782716D03*
X60370Y776861D03*
X64790Y776777D03*
X76880Y126528D03*
X76030Y156152D03*
X81030Y172605D03*
X71510Y164548D03*
X82030Y191733D03*
X85876Y218939D03*
X75560Y218513D03*
X72150Y225148D03*
X78614Y229920D03*
X79217Y232861D03*
X81165Y257717D03*
X82368Y297135D03*
X82031Y523928D03*
X72216Y540493D03*
X96168Y231618D03*
X93200Y300734D03*
X87721Y505817D03*
X98370Y619252D03*
X94070Y618986D03*
Y613841D03*
X97790Y613797D03*
X96200Y616325D03*
X95350Y644088D03*
X95310Y647481D03*
X98480Y646217D03*
X98410Y648878D03*
X104550Y262359D03*
X104270Y265662D03*
X103750Y402740D03*
X103810Y405876D03*
X103870Y399604D03*
X108235Y401017D03*
X111120Y401084D03*
X115727Y405844D03*
X113412Y404826D03*
X113504Y407673D03*
X108026Y492500D03*
X109972Y509321D03*
X125480Y91163D03*
X132400Y88153D03*
X129580Y86837D03*
X129780Y92580D03*
X124150Y94643D03*
X128330Y98360D03*
X125050Y384546D03*
X122120Y386736D03*
X126300Y390369D03*
X133138Y510114D03*
X121644Y509398D03*
X130596Y510042D03*
X124652Y509398D03*
X130703Y512549D03*
X130844Y515128D03*
X128087Y513874D03*
X132960Y550005D03*
X125340Y558090D03*
X132190Y662616D03*
X133607Y686699D03*
X135290Y87664D03*
X140350Y81347D03*
X147160Y242219D03*
X137889Y403348D03*
X141800Y404481D03*
X141847Y401820D03*
X135088Y405060D03*
X135181Y402121D03*
X145295Y404388D03*
X145284Y401507D03*
X135300Y468444D03*
X145020Y576001D03*
X148140Y660112D03*
X144631Y735955D03*
X147290Y744113D03*
X145040Y740741D03*
X156255Y45743D03*
X157659Y47891D03*
X164550Y61239D03*
X154581Y308767D03*
X163377Y484538D03*
X152554Y494027D03*
X158406Y500016D03*
X158430Y568437D03*
X153527Y597138D03*
X153712Y610917D03*
X153330Y599935D03*
X153955Y620760D03*
X162668Y631897D03*
X164812Y662579D03*
X154970Y736966D03*
X161981Y730784D03*
X158881D03*
X162640Y743927D03*
X158970D03*
X154400Y744337D03*
X155230Y740259D03*
X168040Y61462D03*
X165690Y98835D03*
X171950Y105105D03*
X175921Y301920D03*
X178921D03*
X178660Y388418D03*
X171934Y386364D03*
X176371Y404721D03*
X177525Y451946D03*
X180125D03*
X178961Y448138D03*
X176220Y448247D03*
X171616Y467804D03*
X167530Y631935D03*
X177038Y647135D03*
X166388Y647435D03*
X171180Y652009D03*
X171270Y655650D03*
X169531Y710542D03*
X165599Y730476D03*
X167568Y743335D03*
X188418Y278887D03*
X191054Y294424D03*
X183254Y295023D03*
X181921Y301920D03*
X191949Y301987D03*
X188810Y301998D03*
X190557Y325701D03*
X184927Y383876D03*
X184523Y441915D03*
X181923Y445044D03*
Y442544D03*
X188654Y573395D03*
X182480Y566819D03*
X181744Y694829D03*
X181950Y698191D03*
X190375Y695624D03*
X191150Y724108D03*
X206273Y98364D03*
X209449Y281098D03*
Y287398D03*
Y290548D03*
X203149Y287398D03*
X206299D03*
X196867Y294342D03*
X206299Y306298D03*
Y303148D03*
X203166Y312577D03*
X197938Y376839D03*
X205790Y387003D03*
X200459Y487253D03*
X210790Y566926D03*
X196907Y605012D03*
X197030Y598535D03*
X197582Y703474D03*
X200692Y704081D03*
X211236Y695586D03*
X197243Y697899D03*
X205440Y712510D03*
X211897Y723870D03*
X205883Y724373D03*
X200817Y724180D03*
X214573Y93771D03*
X217040Y103121D03*
X227517Y244187D03*
X225973Y265197D03*
X213138Y274187D03*
X225160Y293676D03*
X225199Y290548D03*
Y284248D03*
X222049Y287398D03*
X212599D03*
X215749Y290548D03*
X225199Y306298D03*
Y312598D03*
X222049Y306298D03*
X218899D03*
X222049Y299998D03*
X212610Y306305D03*
X224108Y388029D03*
X216633Y384989D03*
X213994Y466054D03*
X218950Y565589D03*
X223453Y578087D03*
X216590Y570850D03*
X220428Y580271D03*
X212635Y665604D03*
X236360Y93931D03*
X231910Y105731D03*
X235190Y96905D03*
X230749Y160807D03*
X230650Y164566D03*
X230890Y169424D03*
X231000Y173381D03*
X230100Y187389D03*
X230140Y197240D03*
X241613Y265197D03*
X233793Y266697D03*
Y257697D03*
X233904Y252772D03*
X234649Y281098D03*
X237865Y281131D03*
X231450Y290583D03*
X237760Y293692D03*
X237799Y287398D03*
X240949Y290548D03*
Y287398D03*
X231499Y284248D03*
Y296848D03*
Y293698D03*
Y299998D03*
X237799Y312598D03*
X231499D03*
X240949Y309448D03*
X231567Y321742D03*
X232782Y327096D03*
X228729Y385227D03*
X239228Y393291D03*
X243209Y574018D03*
X243743Y636514D03*
X239084Y696252D03*
X233954Y697395D03*
X242680Y712337D03*
X234960Y714064D03*
X247870Y105821D03*
X259518Y252358D03*
X249433Y257697D03*
X246467Y255442D03*
X244099Y281098D03*
X254234Y281622D03*
X250399Y281098D03*
X244110Y290505D03*
X257447Y287117D03*
X244099Y287398D03*
X250399D03*
X253549Y290548D03*
X247249Y296848D03*
X244099D03*
X254007Y306819D03*
X247290Y327694D03*
X256276Y322652D03*
X247789Y322910D03*
X256532Y384895D03*
X247797Y406029D03*
X250297D03*
X252797D03*
X245297D03*
X252670Y443592D03*
X245860Y575049D03*
X249013Y628514D03*
X251803Y636704D03*
X254773Y644424D03*
X254303Y636744D03*
X256463Y639364D03*
X252173Y644344D03*
X249083Y636664D03*
X256513Y642494D03*
X246553Y636684D03*
X251451Y697465D03*
X268809Y16400D03*
X272010Y40553D03*
X274510D03*
X268702Y107928D03*
X260045Y309615D03*
X272967Y325842D03*
X275517D03*
X270293Y330540D03*
X272964Y330669D03*
X273477Y385100D03*
X261663Y385193D03*
X267993Y390695D03*
X271720Y422587D03*
X269630Y424884D03*
X274180Y424966D03*
X275256Y445753D03*
X271035Y443051D03*
X273735Y443034D03*
X268717Y606015D03*
X261967Y608638D03*
Y605638D03*
X260064Y602993D03*
X261967Y614638D03*
X263467Y626638D03*
X269428Y622966D03*
X261967Y617638D03*
X263467Y623638D03*
X272460Y687889D03*
X272650Y693742D03*
X260680Y712988D03*
X278660Y10073D03*
X287599Y108831D03*
X278880Y108482D03*
X278067Y325842D03*
X285794Y339063D03*
X288687Y385290D03*
X281864Y386178D03*
X284687Y386769D03*
X276400Y422341D03*
X280010Y422279D03*
X281190Y424966D03*
X278080Y424760D03*
X286210Y444926D03*
X289630Y444828D03*
X283212Y442286D03*
X286100Y442298D03*
X288742Y442090D03*
X287970Y446705D03*
X282000Y444966D03*
X279112Y444954D03*
X276626Y442913D03*
X279990Y442071D03*
X280210Y460762D03*
X280380Y467284D03*
X278990Y464793D03*
X275560Y697804D03*
X279060Y693306D03*
X299590Y121289D03*
X299850Y124708D03*
X297073Y329159D03*
X306820Y342146D03*
X305446Y359450D03*
X291382Y385457D03*
X291860Y442927D03*
X292170Y445986D03*
X306229Y600263D03*
X305602Y620685D03*
Y618185D03*
X299629Y623877D03*
X306294Y667156D03*
Y675156D03*
X297770Y674720D03*
X305979Y691156D03*
X306145Y683156D03*
X305979Y687156D03*
X306294Y679156D03*
X292970Y682450D03*
X303681Y714421D03*
X296885Y718059D03*
X297223Y715523D03*
X291318Y713875D03*
X313583Y122387D03*
X313980Y335813D03*
X319807Y346376D03*
X317140Y421775D03*
X319478Y429389D03*
X318950Y432473D03*
X318678Y540966D03*
X321828Y541682D03*
X313419Y594040D03*
X313227Y590232D03*
X310919Y594040D03*
X310627Y590232D03*
X312641Y611556D03*
X307996Y611536D03*
X312656Y606881D03*
X307994Y606886D03*
X308102Y620685D03*
Y618185D03*
X320367Y618071D03*
X314910Y627222D03*
X317722Y614646D03*
X311382Y635432D03*
X307113Y713003D03*
X309531Y714298D03*
X312972Y712693D03*
X318090Y712846D03*
X336340Y99265D03*
X323032Y122237D03*
X334478Y299604D03*
X337293Y316660D03*
X332700Y333089D03*
X327058Y358376D03*
X323040Y354485D03*
X326190Y448621D03*
X329120Y449203D03*
X327780Y445819D03*
X331360Y447306D03*
X324927Y546013D03*
X328592Y541146D03*
X328352Y545412D03*
X325588Y541447D03*
X323931Y589733D03*
X328930Y611691D03*
X335915Y675011D03*
X333180Y665611D03*
X335130Y670744D03*
X334313Y663113D03*
X327500Y667244D03*
X324970Y665128D03*
X337030Y677894D03*
X346600Y38561D03*
X346150Y36030D03*
X340792Y307107D03*
X353841Y306194D03*
X339370Y329176D03*
X341910Y325739D03*
X344720D03*
X339600Y332076D03*
X343880Y356989D03*
X349110Y375767D03*
X352890Y479656D03*
X348000Y479150D03*
X352260Y483029D03*
X352160Y502138D03*
X351250Y499752D03*
X353400Y507260D03*
X353460Y504536D03*
X348190Y511550D03*
X353120Y510003D03*
X353260Y688757D03*
X341190Y712379D03*
X364220Y296795D03*
X365970Y299194D03*
X369280Y300916D03*
X365026Y332478D03*
X368660Y449478D03*
X369500Y445873D03*
X368825Y539776D03*
X369918Y592253D03*
X369848Y588903D03*
X368200Y672132D03*
X368100Y668133D03*
X367066Y681094D03*
X361580Y703860D03*
X363590Y702324D03*
X374030Y95000D03*
X374040Y304980D03*
X373640Y301078D03*
X370460Y305908D03*
X371090Y303487D03*
X372320Y439514D03*
X371950Y430527D03*
X378910Y430874D03*
X371080Y448276D03*
X372710Y445705D03*
X385410Y566122D03*
X373448Y589053D03*
X373518Y592403D03*
X383034Y640267D03*
X373680Y662417D03*
X376946Y689985D03*
X377100Y697218D03*
X401220Y65155D03*
X391190Y104173D03*
X388860Y98010D03*
X392076Y470970D03*
X387080Y486400D03*
X385940Y482478D03*
X388890Y480439D03*
X386410Y477576D03*
X389670Y477262D03*
X396520Y567444D03*
X393596Y567630D03*
X401353Y624007D03*
X395701Y637430D03*
X399440Y637340D03*
X399829Y690191D03*
X400968Y686699D03*
X404310Y65213D03*
X405348Y506316D03*
X406884Y594176D03*
X406881Y591322D03*
X410085Y618329D03*
X409520Y637387D03*
X414760Y636225D03*
X415730Y710897D03*
X428747Y463314D03*
Y468770D03*
X420245Y636004D03*
X417422Y637592D03*
X430813Y687156D03*
X427210Y691934D03*
X426391Y701173D03*
X423242Y707949D03*
X425590Y695895D03*
X421350Y694003D03*
X441498Y266731D03*
X441230Y587341D03*
X447830Y588739D03*
X446378Y582681D03*
X437100Y643793D03*
X446500Y645075D03*
X443850Y634754D03*
X434681Y642639D03*
X445270Y660832D03*
X447210Y665143D03*
X447161Y673564D03*
X444458Y669350D03*
X458120Y44721D03*
X455292Y162797D03*
X455470Y166963D03*
X452669Y157140D03*
X455913Y178698D03*
X454763Y183503D03*
X453340Y185670D03*
X457482Y183523D03*
X459000Y200500D03*
X453620Y245162D03*
X456800Y259233D03*
X449402Y515514D03*
X451325Y525981D03*
X450778Y583106D03*
X463178Y647483D03*
X458820Y674137D03*
X478000Y212500D03*
X476320Y629280D03*
X469229Y638135D03*
X475820Y635422D03*
X474946Y659376D03*
X468540Y655799D03*
X469977Y676496D03*
X468260Y664366D03*
X469467Y679915D03*
X487030Y68075D03*
X492955Y99440D03*
X487020Y119754D03*
X487740Y161235D03*
X488220Y157515D03*
X494210Y175035D03*
X487464Y198566D03*
X491320Y231809D03*
X484780Y314090D03*
X494850Y315733D03*
X489962Y540849D03*
X491380Y639279D03*
X495900Y641804D03*
X492310Y650516D03*
X482180Y646278D03*
X491044Y667604D03*
X491060Y671604D03*
X502900Y57670D03*
X497430Y124024D03*
X502183Y156709D03*
X500963Y162261D03*
X501040Y177297D03*
X498940Y179744D03*
X502999Y180541D03*
X499225Y205296D03*
X499405Y242877D03*
X507000Y239000D03*
X499551Y429636D03*
X509464Y450265D03*
X501331Y528932D03*
X500138Y563025D03*
X500438Y574925D03*
X500419Y578644D03*
X505738Y590525D03*
X498350Y627580D03*
X504836Y657097D03*
X503680Y659666D03*
X498040Y675306D03*
X498870Y668324D03*
X506376Y687436D03*
X513120Y72069D03*
X525570Y124623D03*
X518725Y170525D03*
X512160Y217073D03*
X515675Y234555D03*
X524675Y234766D03*
X517189Y226229D03*
X517617Y422944D03*
X513140Y452621D03*
X519440Y452321D03*
X526340D03*
X513140Y459721D03*
Y466021D03*
X525640Y473021D03*
X519640D03*
X513140D03*
X518938Y540425D03*
X524638Y590225D03*
X520228Y590335D03*
X511910Y638722D03*
X526610Y672286D03*
X517443Y717011D03*
X517775Y711203D03*
X522865Y711178D03*
X514498Y716473D03*
X532955Y108669D03*
X538294Y159415D03*
X538525Y213425D03*
X536972Y242993D03*
X536476Y238993D03*
X530940Y422207D03*
X533040Y453221D03*
X533740Y458021D03*
Y465021D03*
Y473021D03*
X535729Y476632D03*
X543280Y491040D03*
X530438Y529525D03*
X535776Y590487D03*
X530338Y590325D03*
X541440Y647594D03*
X531970Y650491D03*
X536557Y655498D03*
X539120Y670129D03*
X535272Y711217D03*
X535062Y708679D03*
X530012Y708618D03*
X537503Y710088D03*
X540062Y708779D03*
X551454Y97154D03*
X550040Y243929D03*
X557207Y274828D03*
X551341Y274262D03*
X548470Y378127D03*
X546250Y490302D03*
X551538Y540325D03*
X551338Y544225D03*
X551438Y563825D03*
X551238Y584025D03*
X543850Y590313D03*
X552849Y631652D03*
X555356Y665156D03*
Y669156D03*
X551283Y699243D03*
X545062Y708679D03*
X553193Y724847D03*
X563230Y150222D03*
X569874Y231795D03*
X571650Y625998D03*
X574730Y625521D03*
X570614Y713237D03*
X565062Y708679D03*
X588943Y98963D03*
X589308Y103990D03*
X580501Y138336D03*
X583829Y132232D03*
X583547Y128232D03*
X583970Y144589D03*
X580180Y148894D03*
X579540Y143304D03*
X583707Y220762D03*
X587707Y220728D03*
X589070Y423525D03*
X577000Y620029D03*
X583930Y652439D03*
X579020Y658250D03*
X589050Y680160D03*
X579980Y683140D03*
X576442Y705492D03*
X584312Y710716D03*
X603158Y91535D03*
X601374Y94048D03*
X604543Y94886D03*
X598123Y102023D03*
X595318Y98854D03*
X593850Y103755D03*
X592392Y100623D03*
X595345Y120216D03*
X593277Y179955D03*
X591707Y221095D03*
X604338Y338285D03*
X597440Y391690D03*
X594860Y395088D03*
X605800Y463167D03*
X598670Y508170D03*
X602332Y671156D03*
X600736Y668425D03*
X593142Y663828D03*
X601856Y711479D03*
X606146Y713145D03*
X608306Y359971D03*
X617592Y362539D03*
X620238Y364369D03*
X610580Y448662D03*
X609370Y452974D03*
X610010Y456581D03*
X617980Y460408D03*
X616320Y537066D03*
X612493Y607666D03*
X612370Y614143D03*
X616471Y636215D03*
X607620Y647169D03*
X610693Y679333D03*
X608975Y708094D03*
X612914Y707630D03*
X610540Y697964D03*
X618020Y700000D03*
X609070Y721917D03*
X616070Y720838D03*
X620670Y722216D03*
X626380Y85117D03*
X624020Y83243D03*
X623750Y87130D03*
X626380Y88518D03*
X623725Y90422D03*
X626180Y91919D03*
X623820Y93654D03*
X626320Y96084D03*
X623610Y97125D03*
X626180Y99276D03*
X624889Y357778D03*
X637738Y392034D03*
X637614Y397259D03*
X626250Y450248D03*
X631280Y446007D03*
X628250Y471142D03*
X632680Y466669D03*
X636868Y593141D03*
X630768Y593241D03*
X624468D03*
Y612141D03*
X624368Y605941D03*
Y599741D03*
X629868Y612241D03*
X635968D03*
X630984Y624829D03*
X634137Y639352D03*
X630137Y639312D03*
X639350Y250123D03*
X648838Y349785D03*
X642863Y358010D03*
X653070Y427500D03*
X641690Y443656D03*
X651080Y455238D03*
X652110Y465238D03*
X651840Y460012D03*
X648920Y457851D03*
X646600Y463571D03*
X638350Y507893D03*
X646460Y512967D03*
X645150Y535704D03*
X638166Y560972D03*
X638286Y557415D03*
X646732Y580781D03*
X641870Y580743D03*
X643568Y593241D03*
Y612341D03*
Y606641D03*
Y599541D03*
X648701Y624774D03*
X646737Y639413D03*
X642737D03*
X651226Y666288D03*
X644950Y719110D03*
X666270Y359134D03*
X659543Y377086D03*
X653938Y364885D03*
X658295Y417662D03*
X653649Y417582D03*
X668779Y417135D03*
X662780Y477039D03*
X662630Y500823D03*
X668823Y532470D03*
X668627Y527718D03*
X655445Y591918D03*
X656070Y612743D03*
X655688Y601761D03*
X655873Y615540D03*
X657550Y655072D03*
X665050Y680648D03*
X656650Y713057D03*
X659200Y721454D03*
X657570Y730414D03*
X658860Y727383D03*
X656000Y732400D03*
X677946Y387211D03*
X679138Y397985D03*
X680017Y403143D03*
X682764Y444832D03*
X677070Y444820D03*
X672190Y457216D03*
X674156Y503662D03*
X670940Y612070D03*
X683720Y631732D03*
X675100Y749300D03*
X672710Y746235D03*
X672500Y749179D03*
X684500Y786665D03*
X683520Y789080D03*
Y792080D03*
X696494Y513677D03*
X696891Y507279D03*
X700719Y516954D03*
X687660Y631799D03*
X685640Y634154D03*
X711676Y51019D03*
X701770Y331938D03*
X715328Y481122D03*
X700829Y504041D03*
X701170Y538508D03*
X712732Y631749D03*
X716064D03*
X713742Y634373D03*
X719800Y24920D03*
X718431Y483368D03*
X721290Y484381D03*
X725730Y486788D03*
X729640Y486848D03*
X720150Y491632D03*
X719092Y631682D03*
X717372Y634474D03*
X747600Y323527D03*
X745220Y327250D03*
X738130Y502748D03*
X732817Y489435D03*
X744020Y566143D03*
X744090Y575066D03*
X743951Y578833D03*
X744050Y571834D03*
X747470Y585542D03*
X747460Y582318D03*
X750430Y314330D03*
X750350Y311343D03*
X750700Y323771D03*
X753230Y328262D03*
X759400Y334839D03*
X754850Y335055D03*
X755500Y337791D03*
X751730Y583047D03*
X765250Y357789D03*
X765610Y361194D03*
G54D20*
G01X38493Y-241864D02*
Y-246864D01*
G01X37036Y-241864D02*
X39950D01*
G01X44860Y-246864D02*
X42326D01*
Y-241864D01*
X44860D01*
G01X43846Y-244281D02*
X42326D01*
G01X47426Y-241864D02*
Y-246864D01*
X49960D01*
G01X53793Y-247031D02*
X53666Y-246947D01*
Y-246781D01*
X53793Y-246697D01*
X53920Y-246781D01*
Y-246947D01*
X53793Y-247031D01*
G01Y-244781D02*
X53666Y-244697D01*
Y-244531D01*
X53793Y-244447D01*
X53920Y-244531D01*
Y-244697D01*
X53793Y-244781D01*
G01X58576Y-248531D02*
X57943Y-247697D01*
X57626Y-246864D01*
Y-243531D01*
X57943Y-242697D01*
X58576Y-241864D01*
G01X63993D02*
X63486Y-242031D01*
X63106Y-242447D01*
X62853Y-242947D01*
X62663Y-243614D01*
X62600Y-244364D01*
X62663Y-245114D01*
X62853Y-245781D01*
X63106Y-246281D01*
X63486Y-246697D01*
X63993Y-246864D01*
X64500Y-246697D01*
X64880Y-246281D01*
X65133Y-245781D01*
X65323Y-245114D01*
X65386Y-244364D01*
X65323Y-243614D01*
X65133Y-242947D01*
X64880Y-242447D01*
X64500Y-242031D01*
X63993Y-241864D01*
G01X67700Y-245864D02*
X68080Y-246447D01*
X68586Y-246781D01*
X69156Y-246864D01*
X69663Y-246781D01*
X70170Y-246364D01*
X70486Y-245864D01*
X70550Y-245364D01*
X70423Y-244781D01*
X69980Y-244364D01*
X69536Y-244197D01*
X68966D01*
G01X69536D02*
X69916Y-243947D01*
X70233Y-243531D01*
X70360Y-243031D01*
X70233Y-242531D01*
X69916Y-242114D01*
X69346Y-241864D01*
X68776Y-241947D01*
X68206Y-242281D01*
G01X74510Y-248531D02*
X75143Y-247697D01*
X75460Y-246864D01*
Y-243531D01*
X75143Y-242697D01*
X74510Y-241864D01*
G01X77900Y-245864D02*
X78280Y-246447D01*
X78786Y-246781D01*
X79356Y-246864D01*
X79863Y-246781D01*
X80370Y-246364D01*
X80686Y-245864D01*
X80750Y-245364D01*
X80623Y-244781D01*
X80180Y-244364D01*
X79736Y-244197D01*
X79166D01*
G01X79736D02*
X80116Y-243947D01*
X80433Y-243531D01*
X80560Y-243031D01*
X80433Y-242531D01*
X80116Y-242114D01*
X79546Y-241864D01*
X78976Y-241947D01*
X78406Y-242281D01*
G01X83190Y-242697D02*
X83570Y-242197D01*
X84013Y-241947D01*
X84520Y-241864D01*
X85153Y-242031D01*
X85596Y-242447D01*
X85723Y-242947D01*
X85660Y-243447D01*
X85406Y-243864D01*
X84140Y-244697D01*
X83570Y-245281D01*
X83190Y-246114D01*
X83063Y-246864D01*
X85723D01*
G01X89366D02*
X89493Y-245781D01*
X89683Y-244864D01*
X89936Y-244031D01*
X90253Y-243114D01*
X90760Y-241864D01*
X88226D01*
G01X93770Y-245197D02*
X95416D01*
G01X98490Y-242697D02*
X98870Y-242197D01*
X99313Y-241947D01*
X99820Y-241864D01*
X100453Y-242031D01*
X100896Y-242447D01*
X101023Y-242947D01*
X100960Y-243447D01*
X100706Y-243864D01*
X99440Y-244697D01*
X98870Y-245281D01*
X98490Y-246114D01*
X98363Y-246864D01*
X101023D01*
G01X103400Y-245864D02*
X103780Y-246447D01*
X104286Y-246781D01*
X104856Y-246864D01*
X105363Y-246781D01*
X105870Y-246364D01*
X106186Y-245864D01*
X106250Y-245364D01*
X106123Y-244781D01*
X105680Y-244364D01*
X105236Y-244197D01*
X104666D01*
G01X105236D02*
X105616Y-243947D01*
X105933Y-243531D01*
X106060Y-243031D01*
X105933Y-242531D01*
X105616Y-242114D01*
X105046Y-241864D01*
X104476Y-241947D01*
X103906Y-242281D01*
G01X110653Y-246864D02*
Y-241864D01*
X108310Y-245447D01*
X111476D01*
G01X113600Y-246114D02*
X113980Y-246531D01*
X114423Y-246781D01*
X114993Y-246864D01*
X115563Y-246697D01*
X116006Y-246364D01*
X116323Y-245781D01*
X116386Y-245114D01*
X116260Y-244447D01*
X115943Y-244031D01*
X115500Y-243697D01*
X115056Y-243614D01*
X114613Y-243697D01*
X114043Y-244031D01*
X114233Y-241864D01*
X115943D01*
G01X123990Y-246864D02*
Y-241864D01*
X126396D01*
G01X125510Y-244281D02*
X123990D01*
G01X128710Y-246864D02*
X130293Y-241864D01*
X131876Y-246864D01*
G01X131306Y-245114D02*
X129280D01*
G01X134063Y-246864D02*
X136723Y-241864D01*
G01X134063D02*
X136723Y-246864D01*
G01X140493Y-247031D02*
X140366Y-246947D01*
Y-246781D01*
X140493Y-246697D01*
X140620Y-246781D01*
Y-246947D01*
X140493Y-247031D01*
G01Y-244781D02*
X140366Y-244697D01*
Y-244531D01*
X140493Y-244447D01*
X140620Y-244531D01*
Y-244697D01*
X140493Y-244781D01*
G01X145276Y-248531D02*
X144643Y-247697D01*
X144326Y-246864D01*
Y-243531D01*
X144643Y-242697D01*
X145276Y-241864D01*
G01X150693D02*
X150186Y-242031D01*
X149806Y-242447D01*
X149553Y-242947D01*
X149363Y-243614D01*
X149300Y-244364D01*
X149363Y-245114D01*
X149553Y-245781D01*
X149806Y-246281D01*
X150186Y-246697D01*
X150693Y-246864D01*
X151200Y-246697D01*
X151580Y-246281D01*
X151833Y-245781D01*
X152023Y-245114D01*
X152086Y-244364D01*
X152023Y-243614D01*
X151833Y-242947D01*
X151580Y-242447D01*
X151200Y-242031D01*
X150693Y-241864D01*
G01X154400Y-245864D02*
X154780Y-246447D01*
X155286Y-246781D01*
X155856Y-246864D01*
X156363Y-246781D01*
X156870Y-246364D01*
X157186Y-245864D01*
X157250Y-245364D01*
X157123Y-244781D01*
X156680Y-244364D01*
X156236Y-244197D01*
X155666D01*
G01X156236D02*
X156616Y-243947D01*
X156933Y-243531D01*
X157060Y-243031D01*
X156933Y-242531D01*
X156616Y-242114D01*
X156046Y-241864D01*
X155476Y-241947D01*
X154906Y-242281D01*
G01X161210Y-248531D02*
X161843Y-247697D01*
X162160Y-246864D01*
Y-243531D01*
X161843Y-242697D01*
X161210Y-241864D01*
G01X164600Y-245864D02*
X164980Y-246447D01*
X165486Y-246781D01*
X166056Y-246864D01*
X166563Y-246781D01*
X167070Y-246364D01*
X167386Y-245864D01*
X167450Y-245364D01*
X167323Y-244781D01*
X166880Y-244364D01*
X166436Y-244197D01*
X165866D01*
G01X166436D02*
X166816Y-243947D01*
X167133Y-243531D01*
X167260Y-243031D01*
X167133Y-242531D01*
X166816Y-242114D01*
X166246Y-241864D01*
X165676Y-241947D01*
X165106Y-242281D01*
G01X170016Y-246281D02*
X170460Y-246697D01*
X170966Y-246864D01*
X171473Y-246697D01*
X171916Y-246197D01*
X172233Y-245447D01*
X172360Y-244697D01*
Y-243781D01*
X172233Y-243031D01*
X171916Y-242364D01*
X171536Y-242031D01*
X171093Y-241864D01*
X170586Y-242031D01*
X170206Y-242364D01*
X169953Y-242864D01*
X169826Y-243531D01*
X169953Y-244114D01*
X170270Y-244697D01*
X170650Y-245031D01*
X171093Y-245114D01*
X171600Y-244947D01*
X171980Y-244531D01*
X172360Y-243781D01*
G01X176066Y-246864D02*
X176193Y-245781D01*
X176383Y-244864D01*
X176636Y-244031D01*
X176953Y-243114D01*
X177460Y-241864D01*
X174926D01*
G01X180470Y-245197D02*
X182116D01*
G01X185000Y-245864D02*
X185380Y-246447D01*
X185886Y-246781D01*
X186456Y-246864D01*
X186963Y-246781D01*
X187470Y-246364D01*
X187786Y-245864D01*
X187850Y-245364D01*
X187723Y-244781D01*
X187280Y-244364D01*
X186836Y-244197D01*
X186266D01*
G01X186836D02*
X187216Y-243947D01*
X187533Y-243531D01*
X187660Y-243031D01*
X187533Y-242531D01*
X187216Y-242114D01*
X186646Y-241864D01*
X186076Y-241947D01*
X185506Y-242281D01*
G01X190290Y-244781D02*
X190733Y-244197D01*
X191113Y-243864D01*
X191620Y-243697D01*
X192063Y-243864D01*
X192380Y-244197D01*
X192633Y-244697D01*
X192696Y-245281D01*
X192633Y-245781D01*
X192380Y-246281D01*
X192000Y-246697D01*
X191556Y-246864D01*
X191050Y-246697D01*
X190606Y-246197D01*
X190353Y-245447D01*
X190290Y-244614D01*
X190416Y-243531D01*
X190606Y-242947D01*
X190923Y-242364D01*
X191366Y-241947D01*
X191810Y-241864D01*
X192253Y-242031D01*
X192570Y-242447D01*
G01X196593Y-246864D02*
Y-241864D01*
X195833Y-242864D01*
G01Y-246864D02*
X197353D01*
G01X202453D02*
Y-241864D01*
X200110Y-245447D01*
X203276D01*
G01X26493Y-176864D02*
Y-251864D01*
X526493D01*
Y-176864D01*
X26493D01*
G01X221493D02*
Y-251864D01*
G01Y-226864D02*
X324493D01*
Y-201864D01*
G01X221493D02*
X324493D01*
G01X332000Y-236864D02*
Y-231864D01*
X333266D01*
X333773Y-232114D01*
X334153Y-232447D01*
X334470Y-232947D01*
X334723Y-233531D01*
X334786Y-234364D01*
X334723Y-235197D01*
X334470Y-235781D01*
X334153Y-236281D01*
X333773Y-236614D01*
X333266Y-236864D01*
X332000D01*
G01X336910D02*
X338493Y-231864D01*
X340076Y-236864D01*
G01X339506Y-235114D02*
X337480D01*
G01X343593Y-231864D02*
Y-236864D01*
G01X342136Y-231864D02*
X345050D01*
G01X349960Y-236864D02*
X347426D01*
Y-231864D01*
X349960D01*
G01X348946Y-234281D02*
X347426D01*
G01X353793Y-237031D02*
X353666Y-236947D01*
Y-236781D01*
X353793Y-236697D01*
X353920Y-236781D01*
Y-236947D01*
X353793Y-237031D01*
G01Y-234781D02*
X353666Y-234697D01*
Y-234531D01*
X353793Y-234447D01*
X353920Y-234531D01*
Y-234697D01*
X353793Y-234781D01*
G01X326493Y-176864D02*
Y-251864D01*
G01X324493Y-176864D02*
Y-251864D01*
G01X326493Y-226864D02*
X526493D01*
G01X332126Y-211864D02*
Y-206864D01*
X333646D01*
X334153Y-207114D01*
X334533Y-207697D01*
X334660Y-208364D01*
X334533Y-209031D01*
X334216Y-209531D01*
X333646Y-209781D01*
X332126D01*
G01X337353Y-212031D02*
X339633Y-206864D01*
G01X342136Y-211864D02*
Y-206864D01*
X345050Y-211864D01*
Y-206864D01*
G01X348693Y-212031D02*
X348566Y-211947D01*
Y-211781D01*
X348693Y-211697D01*
X348820Y-211781D01*
Y-211947D01*
X348693Y-212031D01*
G01Y-209781D02*
X348566Y-209697D01*
Y-209531D01*
X348693Y-209447D01*
X348820Y-209531D01*
Y-209697D01*
X348693Y-209781D01*
G01X326493Y-201864D02*
X526493D01*
G01X332126Y-186864D02*
Y-181864D01*
X333646D01*
X334153Y-182114D01*
X334533Y-182697D01*
X334660Y-183364D01*
X334533Y-184031D01*
X334216Y-184531D01*
X333646Y-184781D01*
X332126D01*
G01X337226Y-186864D02*
Y-181864D01*
X338810D01*
X339316Y-182114D01*
X339633Y-182447D01*
X339760Y-183114D01*
X339633Y-183781D01*
X339253Y-184197D01*
X338810Y-184447D01*
X337226D01*
G01X338810D02*
X339760Y-186864D01*
G01X343593D02*
X343086Y-186781D01*
X342643Y-186447D01*
X342263Y-185947D01*
X342010Y-185364D01*
X341883Y-184697D01*
Y-184031D01*
X342010Y-183364D01*
X342263Y-182781D01*
X342643Y-182281D01*
X343086Y-181947D01*
X343593Y-181864D01*
X344100Y-181947D01*
X344543Y-182281D01*
X344923Y-182781D01*
X345176Y-183364D01*
X345303Y-184031D01*
Y-184697D01*
X345176Y-185364D01*
X344923Y-185947D01*
X344543Y-186447D01*
X344100Y-186781D01*
X343593Y-186864D01*
G01X347426Y-185864D02*
X347743Y-186364D01*
X348123Y-186697D01*
X348566Y-186864D01*
X349073Y-186697D01*
X349453Y-186364D01*
X349833Y-185864D01*
X349960Y-185197D01*
Y-181864D01*
G01X355060Y-186864D02*
X352526D01*
Y-181864D01*
X355060D01*
G01X354046Y-184281D02*
X352526D01*
G01X360286Y-182281D02*
X359906Y-182031D01*
X359463Y-181864D01*
X358956D01*
X358386Y-182114D01*
X357943Y-182531D01*
X357626Y-183031D01*
X357373Y-183864D01*
X357310Y-184614D01*
X357436Y-185364D01*
X357626Y-185864D01*
X358006Y-186364D01*
X358450Y-186697D01*
X358893Y-186864D01*
X359336D01*
X359780Y-186697D01*
X360160Y-186447D01*
X360476Y-186114D01*
G01X363993Y-181864D02*
Y-186864D01*
G01X362536Y-181864D02*
X365450D01*
G01X369093Y-187031D02*
X368966Y-186947D01*
Y-186781D01*
X369093Y-186697D01*
X369220Y-186781D01*
Y-186947D01*
X369093Y-187031D01*
G01Y-184781D02*
X368966Y-184697D01*
Y-184531D01*
X369093Y-184447D01*
X369220Y-184531D01*
Y-184697D01*
X369093Y-184781D01*
G01X447126Y-236864D02*
Y-231864D01*
X448710D01*
X449216Y-232114D01*
X449533Y-232447D01*
X449660Y-233114D01*
X449533Y-233781D01*
X449153Y-234197D01*
X448710Y-234447D01*
X447126D01*
G01X448710D02*
X449660Y-236864D01*
G01X454760D02*
X452226D01*
Y-231864D01*
X454760D01*
G01X453746Y-234281D02*
X452226D01*
G01X457010Y-231864D02*
X458593Y-236864D01*
X460176Y-231864D01*
G01X463693Y-237031D02*
X463566Y-236947D01*
Y-236781D01*
X463693Y-236697D01*
X463820Y-236781D01*
Y-236947D01*
X463693Y-237031D01*
G01Y-234781D02*
X463566Y-234697D01*
Y-234531D01*
X463693Y-234447D01*
X463820Y-234531D01*
Y-234697D01*
X463693Y-234781D01*
G01X441493Y-226864D02*
Y-251864D01*
G01X490493Y-226864D02*
Y-251864D01*
G01X-1043962Y-705877D02*
Y2342823D01*
X2300638D01*
Y-705877D01*
X-1043962D01*
G01X37198Y-238524D02*
X37825Y-239049D01*
X38530Y-239364D01*
X39156D01*
X39783Y-239049D01*
X40253Y-238524D01*
X40488Y-237789D01*
X40331Y-237054D01*
X39940Y-236424D01*
X39235Y-236004D01*
X38295Y-235794D01*
X37746Y-235374D01*
X37511Y-234639D01*
X37668Y-233904D01*
X38060Y-233379D01*
X38608Y-233064D01*
X39156D01*
X39705Y-233274D01*
X40175Y-233799D01*
G01X43498Y-239364D02*
Y-233064D01*
G01X46788D02*
Y-239364D01*
G01Y-236214D02*
X43498D01*
G01X50503Y-233064D02*
X52383D01*
G01X51443D02*
Y-239364D01*
G01X50503D02*
X52383D01*
G01X59310D02*
X56176D01*
Y-233064D01*
X59310D01*
G01X58056Y-236109D02*
X56176D01*
G01X62241Y-239364D02*
Y-233064D01*
X65845Y-239364D01*
Y-233064D01*
G01X70186Y-240519D02*
X70500Y-239154D01*
G01X76643Y-233064D02*
Y-239364D01*
G01X74841Y-233064D02*
X78445D01*
G01X80985Y-239364D02*
X82943Y-233064D01*
X84901Y-239364D01*
G01X84196Y-237159D02*
X81690D01*
G01X88303Y-233064D02*
X90183D01*
G01X89243D02*
Y-239364D01*
G01X88303D02*
X90183D01*
G01X93193Y-233064D02*
X94290Y-239364D01*
X95543Y-233064D01*
X96796Y-239364D01*
X97893Y-233064D01*
G01X99885Y-239364D02*
X101843Y-233064D01*
X103801Y-239364D01*
G01X103096Y-237159D02*
X100590D01*
G01X106341Y-239364D02*
Y-233064D01*
X109945Y-239364D01*
Y-233064D01*
G01X119176Y-239364D02*
Y-233064D01*
X121135D01*
X121761Y-233379D01*
X122153Y-233799D01*
X122310Y-234639D01*
X122153Y-235479D01*
X121683Y-236004D01*
X121135Y-236319D01*
X119176D01*
G01X121135D02*
X122310Y-239364D01*
G01X127043Y-239574D02*
X126886Y-239469D01*
Y-239259D01*
X127043Y-239154D01*
X127200Y-239259D01*
Y-239469D01*
X127043Y-239574D01*
G01X133343Y-239364D02*
X132716Y-239259D01*
X132168Y-238839D01*
X131698Y-238209D01*
X131385Y-237474D01*
X131228Y-236634D01*
Y-235794D01*
X131385Y-234954D01*
X131698Y-234219D01*
X132168Y-233589D01*
X132716Y-233169D01*
X133343Y-233064D01*
X133970Y-233169D01*
X134518Y-233589D01*
X134988Y-234219D01*
X135301Y-234954D01*
X135458Y-235794D01*
Y-236634D01*
X135301Y-237474D01*
X134988Y-238209D01*
X134518Y-238839D01*
X133970Y-239259D01*
X133343Y-239364D01*
G01X139643Y-239574D02*
X139486Y-239469D01*
Y-239259D01*
X139643Y-239154D01*
X139800Y-239259D01*
Y-239469D01*
X139643Y-239574D01*
G01X147666Y-233589D02*
X147196Y-233274D01*
X146648Y-233064D01*
X146021D01*
X145316Y-233379D01*
X144768Y-233904D01*
X144376Y-234534D01*
X144063Y-235584D01*
X143985Y-236529D01*
X144141Y-237474D01*
X144376Y-238104D01*
X144846Y-238734D01*
X145395Y-239154D01*
X145943Y-239364D01*
X146491D01*
X147040Y-239154D01*
X147510Y-238839D01*
X147901Y-238419D01*
G01X152243Y-239574D02*
X152086Y-239469D01*
Y-239259D01*
X152243Y-239154D01*
X152400Y-239259D01*
Y-239469D01*
X152243Y-239574D01*
G01X37120Y-229364D02*
Y-223064D01*
G01X40096D02*
X37120Y-226949D01*
G01X40566Y-229364D02*
X38451Y-225164D01*
G01X43420Y-223064D02*
Y-227579D01*
X43733Y-228524D01*
X44360Y-229154D01*
X45143Y-229364D01*
X45926Y-229154D01*
X46553Y-228524D01*
X46866Y-227579D01*
Y-223064D01*
G01X53010Y-229364D02*
X49876D01*
Y-223064D01*
X53010D01*
G01X51756Y-226109D02*
X49876D01*
G01X56803Y-223064D02*
X58683D01*
G01X57743D02*
Y-229364D01*
G01X56803D02*
X58683D01*
G01X68698Y-228524D02*
X69325Y-229049D01*
X70030Y-229364D01*
X70656D01*
X71283Y-229049D01*
X71753Y-228524D01*
X71988Y-227789D01*
X71831Y-227054D01*
X71440Y-226424D01*
X70735Y-226004D01*
X69795Y-225794D01*
X69246Y-225374D01*
X69011Y-224639D01*
X69168Y-223904D01*
X69560Y-223379D01*
X70108Y-223064D01*
X70656D01*
X71205Y-223274D01*
X71675Y-223799D01*
G01X74998Y-229364D02*
Y-223064D01*
G01X78288D02*
Y-229364D01*
G01Y-226214D02*
X74998D01*
G01X80985Y-229364D02*
X82943Y-223064D01*
X84901Y-229364D01*
G01X84196Y-227159D02*
X81690D01*
G01X87441Y-229364D02*
Y-223064D01*
X91045Y-229364D01*
Y-223064D01*
G01X100198Y-229364D02*
Y-223064D01*
G01X103488D02*
Y-229364D01*
G01Y-226214D02*
X100198D01*
G01X106498Y-228524D02*
X107125Y-229049D01*
X107830Y-229364D01*
X108456D01*
X109083Y-229049D01*
X109553Y-228524D01*
X109788Y-227789D01*
X109631Y-227054D01*
X109240Y-226424D01*
X108535Y-226004D01*
X107595Y-225794D01*
X107046Y-225374D01*
X106811Y-224639D01*
X106968Y-223904D01*
X107360Y-223379D01*
X107908Y-223064D01*
X108456D01*
X109005Y-223274D01*
X109475Y-223799D01*
G01X113503Y-223064D02*
X115383D01*
G01X114443D02*
Y-229364D01*
G01X113503D02*
X115383D01*
G01X118785D02*
X120743Y-223064D01*
X122701Y-229364D01*
G01X121996Y-227159D02*
X119490D01*
G01X125241Y-229364D02*
Y-223064D01*
X128845Y-229364D01*
Y-223064D01*
G01X133813Y-226214D02*
X135380D01*
Y-228104D01*
X134910Y-228734D01*
X134361Y-229154D01*
X133578Y-229364D01*
X132795Y-229154D01*
X132246Y-228734D01*
X131776Y-228104D01*
X131463Y-227369D01*
X131306Y-226529D01*
Y-225794D01*
X131463Y-225164D01*
X131776Y-224429D01*
X132246Y-223799D01*
X132716Y-223379D01*
X133343Y-223064D01*
X133891D01*
X134518Y-223274D01*
X134988Y-223694D01*
G01X139486Y-230519D02*
X139800Y-229154D01*
G01X145943Y-223064D02*
Y-229364D01*
G01X144141Y-223064D02*
X147745D01*
G01X150285Y-229364D02*
X152243Y-223064D01*
X154201Y-229364D01*
G01X153496Y-227159D02*
X150990D01*
G01X158543Y-229364D02*
X157916Y-229259D01*
X157368Y-228839D01*
X156898Y-228209D01*
X156585Y-227474D01*
X156428Y-226634D01*
Y-225794D01*
X156585Y-224954D01*
X156898Y-224219D01*
X157368Y-223589D01*
X157916Y-223169D01*
X158543Y-223064D01*
X159170Y-223169D01*
X159718Y-223589D01*
X160188Y-224219D01*
X160501Y-224954D01*
X160658Y-225794D01*
Y-226634D01*
X160501Y-227474D01*
X160188Y-228209D01*
X159718Y-228839D01*
X159170Y-229259D01*
X158543Y-229364D01*
G01X171143D02*
Y-226529D01*
X169576Y-223064D01*
G01X172710D02*
X171143Y-226529D01*
G01X175720Y-223064D02*
Y-227579D01*
X176033Y-228524D01*
X176660Y-229154D01*
X177443Y-229364D01*
X178226Y-229154D01*
X178853Y-228524D01*
X179166Y-227579D01*
Y-223064D01*
G01X181785Y-229364D02*
X183743Y-223064D01*
X185701Y-229364D01*
G01X184996Y-227159D02*
X182490D01*
G01X188241Y-229364D02*
Y-223064D01*
X191845Y-229364D01*
Y-223064D01*
G01X37041Y-219364D02*
Y-213064D01*
X40645Y-219364D01*
Y-213064D01*
G01X45143Y-219364D02*
X44516Y-219259D01*
X43968Y-218839D01*
X43498Y-218209D01*
X43185Y-217474D01*
X43028Y-216634D01*
Y-215794D01*
X43185Y-214954D01*
X43498Y-214219D01*
X43968Y-213589D01*
X44516Y-213169D01*
X45143Y-213064D01*
X45770Y-213169D01*
X46318Y-213589D01*
X46788Y-214219D01*
X47101Y-214954D01*
X47258Y-215794D01*
Y-216634D01*
X47101Y-217474D01*
X46788Y-218209D01*
X46318Y-218839D01*
X45770Y-219259D01*
X45143Y-219364D01*
G01X51443Y-219574D02*
X51286Y-219469D01*
Y-219259D01*
X51443Y-219154D01*
X51600Y-219259D01*
Y-219469D01*
X51443Y-219574D01*
G01X57743Y-219364D02*
Y-213064D01*
X56803Y-214324D01*
G01Y-219364D02*
X58683D01*
G01X64043D02*
X64591Y-219259D01*
X65218Y-218944D01*
X65610Y-218419D01*
X65766Y-217684D01*
X65610Y-216949D01*
X65140Y-216319D01*
X64435Y-216004D01*
X63651D01*
X63181Y-215794D01*
X62790Y-215269D01*
X62633Y-214534D01*
X62868Y-213799D01*
X63416Y-213274D01*
X64043Y-213064D01*
X64670Y-213274D01*
X65218Y-213799D01*
X65453Y-214534D01*
X65296Y-215269D01*
X64905Y-215794D01*
X64435Y-216004D01*
X63651D01*
X62946Y-216319D01*
X62476Y-216949D01*
X62320Y-217684D01*
X62476Y-218419D01*
X62868Y-218944D01*
X63495Y-219259D01*
X64043Y-219364D01*
G01X70343D02*
X70891Y-219259D01*
X71518Y-218944D01*
X71910Y-218419D01*
X72066Y-217684D01*
X71910Y-216949D01*
X71440Y-216319D01*
X70735Y-216004D01*
X69951D01*
X69481Y-215794D01*
X69090Y-215269D01*
X68933Y-214534D01*
X69168Y-213799D01*
X69716Y-213274D01*
X70343Y-213064D01*
X70970Y-213274D01*
X71518Y-213799D01*
X71753Y-214534D01*
X71596Y-215269D01*
X71205Y-215794D01*
X70735Y-216004D01*
X69951D01*
X69246Y-216319D01*
X68776Y-216949D01*
X68620Y-217684D01*
X68776Y-218419D01*
X69168Y-218944D01*
X69795Y-219259D01*
X70343Y-219364D01*
G01X76486Y-220519D02*
X76800Y-219154D01*
G01X80593Y-213064D02*
X81690Y-219364D01*
X82943Y-213064D01*
X84196Y-219364D01*
X85293Y-213064D01*
G01X90810Y-219364D02*
X87676D01*
Y-213064D01*
X90810D01*
G01X89556Y-216109D02*
X87676D01*
G01X93741Y-219364D02*
Y-213064D01*
X97345Y-219364D01*
Y-213064D01*
G01X106498Y-219364D02*
Y-213064D01*
G01X109788D02*
Y-219364D01*
G01Y-216214D02*
X106498D01*
G01X112093Y-213064D02*
X113190Y-219364D01*
X114443Y-213064D01*
X115696Y-219364D01*
X116793Y-213064D01*
G01X118785Y-219364D02*
X120743Y-213064D01*
X122701Y-219364D01*
G01X121996Y-217159D02*
X119490D01*
G01X131855Y-214114D02*
X132325Y-213484D01*
X132873Y-213169D01*
X133500Y-213064D01*
X134283Y-213274D01*
X134831Y-213799D01*
X134988Y-214429D01*
X134910Y-215059D01*
X134596Y-215584D01*
X133030Y-216634D01*
X132325Y-217369D01*
X131855Y-218419D01*
X131698Y-219364D01*
X134988D01*
G01X137841D02*
Y-213064D01*
X141445Y-219364D01*
Y-213064D01*
G01X144220Y-219364D02*
Y-213064D01*
X145786D01*
X146413Y-213379D01*
X146883Y-213799D01*
X147275Y-214429D01*
X147588Y-215164D01*
X147666Y-216214D01*
X147588Y-217264D01*
X147275Y-217999D01*
X146883Y-218629D01*
X146413Y-219049D01*
X145786Y-219364D01*
X144220D01*
G01X156976D02*
Y-213064D01*
X158935D01*
X159561Y-213379D01*
X159953Y-213799D01*
X160110Y-214639D01*
X159953Y-215479D01*
X159483Y-216004D01*
X158935Y-216319D01*
X156976D01*
G01X158935D02*
X160110Y-219364D01*
G01X163120D02*
Y-213064D01*
X164686D01*
X165313Y-213379D01*
X165783Y-213799D01*
X166175Y-214429D01*
X166488Y-215164D01*
X166566Y-216214D01*
X166488Y-217264D01*
X166175Y-217999D01*
X165783Y-218629D01*
X165313Y-219049D01*
X164686Y-219364D01*
X163120D01*
G01X171143Y-219574D02*
X170986Y-219469D01*
Y-219259D01*
X171143Y-219154D01*
X171300Y-219259D01*
Y-219469D01*
X171143Y-219574D01*
G01X61143Y-206664D02*
X58623Y-206247D01*
X56418Y-204581D01*
X54528Y-202081D01*
X53268Y-199164D01*
X52638Y-195831D01*
Y-192497D01*
X53268Y-189164D01*
X54528Y-186247D01*
X56418Y-183748D01*
X58623Y-182081D01*
X61143Y-181664D01*
X63663Y-182081D01*
X65868Y-183748D01*
X67758Y-186247D01*
X69018Y-189164D01*
X69648Y-192497D01*
Y-195831D01*
X69018Y-199164D01*
X67758Y-202081D01*
X65868Y-204581D01*
X63663Y-206247D01*
X61143Y-206664D01*
G01X63663Y-199997D02*
X67443Y-206664D01*
G01X80988Y-189998D02*
Y-201664D01*
X82248Y-204581D01*
X84138Y-206247D01*
X86343Y-206664D01*
X88548Y-206247D01*
X90438Y-204581D01*
X91698Y-201664D01*
G01Y-206664D02*
Y-189998D01*
G01X117213Y-206664D02*
Y-189998D01*
G01Y-192914D02*
X115953Y-191248D01*
X114063Y-190414D01*
X111858Y-189998D01*
X109653Y-190831D01*
X107763Y-192497D01*
X106503Y-194998D01*
X105873Y-198331D01*
X106503Y-201664D01*
X107763Y-204165D01*
X109653Y-205831D01*
X111858Y-206664D01*
X114063Y-206247D01*
X115953Y-204998D01*
X117213Y-203331D01*
G01X131388Y-206664D02*
Y-189998D01*
G01Y-194164D02*
X132648Y-192081D01*
X134538Y-190414D01*
X137058Y-189998D01*
X139263Y-190414D01*
X141153Y-192081D01*
X142098Y-194998D01*
Y-206664D01*
G01X161943Y-181664D02*
Y-206664D01*
G01X157533Y-189998D02*
X166353D01*
G01X192813Y-206664D02*
Y-189998D01*
G01Y-192914D02*
X191553Y-191248D01*
X189663Y-190414D01*
X187458Y-189998D01*
X185253Y-190831D01*
X183363Y-192497D01*
X182103Y-194998D01*
X181473Y-198331D01*
X182103Y-201664D01*
X183363Y-204165D01*
X185253Y-205831D01*
X187458Y-206664D01*
X189663Y-206247D01*
X191553Y-204998D01*
X192813Y-203331D01*
G01X232493Y-186364D02*
Y-194364D01*
X236493D01*
G01X244293D02*
Y-189031D01*
G01Y-189964D02*
X243893Y-189431D01*
X243293Y-189164D01*
X242593Y-189031D01*
X241893Y-189297D01*
X241293Y-189831D01*
X240893Y-190631D01*
X240693Y-191697D01*
X240893Y-192764D01*
X241293Y-193564D01*
X241893Y-194097D01*
X242593Y-194364D01*
X243293Y-194231D01*
X243893Y-193831D01*
X244293Y-193298D01*
G01X248393Y-196764D02*
X248993Y-197031D01*
X249793Y-196764D01*
X250293Y-196231D01*
X250693Y-195564D01*
X251293Y-193431D01*
X252593Y-189031D01*
G01X249393D02*
X251293Y-193431D01*
G01X256993Y-190764D02*
X260193D01*
X259893Y-189831D01*
X259393Y-189297D01*
X258693Y-189031D01*
X257993Y-189164D01*
X257393Y-189564D01*
X256993Y-190497D01*
X256793Y-191298D01*
Y-192097D01*
X256993Y-192897D01*
X257493Y-193697D01*
X258093Y-194231D01*
X258793Y-194364D01*
X259493Y-194097D01*
X260193Y-193298D01*
G01X265093Y-194364D02*
Y-189031D01*
G01Y-190097D02*
X265593Y-189564D01*
X266093Y-189164D01*
X266793Y-189031D01*
X267293Y-189164D01*
X267893Y-189564D01*
G01X254793Y-236364D02*
X257193D01*
G01X255993D02*
Y-244364D01*
G01X254793D02*
X257193D01*
G01X262593D02*
Y-239031D01*
G01Y-240097D02*
X263093Y-239564D01*
X263593Y-239164D01*
X264293Y-239031D01*
X264793Y-239164D01*
X265393Y-239564D01*
G01X270493Y-240764D02*
X273693D01*
X273393Y-239831D01*
X272893Y-239297D01*
X272193Y-239031D01*
X271493Y-239164D01*
X270893Y-239564D01*
X270493Y-240497D01*
X270293Y-241298D01*
Y-242097D01*
X270493Y-242897D01*
X270993Y-243697D01*
X271593Y-244231D01*
X272293Y-244364D01*
X272993Y-244097D01*
X273693Y-243298D01*
G01X278293Y-244364D02*
Y-239031D01*
G01Y-240364D02*
X278693Y-239697D01*
X279293Y-239164D01*
X280093Y-239031D01*
X280793Y-239164D01*
X281393Y-239697D01*
X281693Y-240631D01*
Y-244364D01*
G01X286493Y-240764D02*
X289693D01*
X289393Y-239831D01*
X288893Y-239297D01*
X288193Y-239031D01*
X287493Y-239164D01*
X286893Y-239564D01*
X286493Y-240497D01*
X286293Y-241298D01*
Y-242097D01*
X286493Y-242897D01*
X286993Y-243697D01*
X287593Y-244231D01*
X288293Y-244364D01*
X288993Y-244097D01*
X289693Y-243298D01*
G01X264793Y-211364D02*
X267193D01*
G01X265993D02*
Y-219364D01*
G01X264793D02*
X267193D01*
G01X271693D02*
Y-211364D01*
X276293Y-219364D01*
Y-211364D01*
G01X280093Y-212697D02*
X280693Y-211897D01*
X281393Y-211497D01*
X282193Y-211364D01*
X283193Y-211631D01*
X283893Y-212297D01*
X284093Y-213097D01*
X283993Y-213898D01*
X283593Y-214564D01*
X281593Y-215897D01*
X280693Y-216831D01*
X280093Y-218164D01*
X279893Y-219364D01*
X284093D01*
G01X285793Y-194364D02*
X285993Y-192631D01*
X286293Y-191164D01*
X286693Y-189831D01*
X287193Y-188364D01*
X287993Y-186364D01*
X283993D01*
G01X359093Y-237697D02*
X359693Y-236897D01*
X360393Y-236497D01*
X361193Y-236364D01*
X362193Y-236631D01*
X362893Y-237297D01*
X363093Y-238097D01*
X362993Y-238898D01*
X362593Y-239564D01*
X360593Y-240897D01*
X359693Y-241831D01*
X359093Y-243164D01*
X358893Y-244364D01*
X363093D01*
G01X368993Y-236364D02*
X368193Y-236631D01*
X367593Y-237297D01*
X367193Y-238097D01*
X366893Y-239164D01*
X366793Y-240364D01*
X366893Y-241564D01*
X367193Y-242631D01*
X367593Y-243431D01*
X368193Y-244097D01*
X368993Y-244364D01*
X369793Y-244097D01*
X370393Y-243431D01*
X370793Y-242631D01*
X371093Y-241564D01*
X371193Y-240364D01*
X371093Y-239164D01*
X370793Y-238097D01*
X370393Y-237297D01*
X369793Y-236631D01*
X368993Y-236364D01*
G01X376993Y-244364D02*
Y-236364D01*
X375793Y-237964D01*
G01Y-244364D02*
X378193D01*
G01X383093Y-237697D02*
X383693Y-236897D01*
X384393Y-236497D01*
X385193Y-236364D01*
X386193Y-236631D01*
X386893Y-237297D01*
X387093Y-238097D01*
X386993Y-238898D01*
X386593Y-239564D01*
X384593Y-240897D01*
X383693Y-241831D01*
X383093Y-243164D01*
X382893Y-244364D01*
X387093D01*
G01X391193Y-244631D02*
X394793Y-236364D01*
G01X400993Y-244364D02*
Y-236364D01*
X399793Y-237964D01*
G01Y-244364D02*
X402193D01*
G01X408993Y-236364D02*
X408193Y-236631D01*
X407593Y-237297D01*
X407193Y-238097D01*
X406893Y-239164D01*
X406793Y-240364D01*
X406893Y-241564D01*
X407193Y-242631D01*
X407593Y-243431D01*
X408193Y-244097D01*
X408993Y-244364D01*
X409793Y-244097D01*
X410393Y-243431D01*
X410793Y-242631D01*
X411093Y-241564D01*
X411193Y-240364D01*
X411093Y-239164D01*
X410793Y-238097D01*
X410393Y-237297D01*
X409793Y-236631D01*
X408993Y-236364D01*
G01X415193Y-244631D02*
X418793Y-236364D01*
G01X422793Y-242764D02*
X423393Y-243697D01*
X424193Y-244231D01*
X425093Y-244364D01*
X425893Y-244231D01*
X426693Y-243564D01*
X427193Y-242764D01*
X427293Y-241964D01*
X427093Y-241031D01*
X426393Y-240364D01*
X425693Y-240097D01*
X424793D01*
G01X425693D02*
X426293Y-239697D01*
X426793Y-239031D01*
X426993Y-238231D01*
X426793Y-237431D01*
X426293Y-236764D01*
X425393Y-236364D01*
X424493Y-236497D01*
X423593Y-237031D01*
G01X432993Y-244364D02*
Y-236364D01*
X431793Y-237964D01*
G01Y-244364D02*
X434193D01*
G01X358793Y-219364D02*
Y-211364D01*
X360793D01*
X361593Y-211764D01*
X362193Y-212297D01*
X362693Y-213097D01*
X363093Y-214031D01*
X363193Y-215364D01*
X363093Y-216697D01*
X362693Y-217631D01*
X362193Y-218431D01*
X361593Y-218964D01*
X360793Y-219364D01*
X358793D01*
G01X366493D02*
X368993Y-211364D01*
X371493Y-219364D01*
G01X370593Y-216564D02*
X367393D01*
G01X376993Y-211364D02*
Y-219364D01*
G01X374693Y-211364D02*
X379293D01*
G01X383093Y-216031D02*
X383793Y-215097D01*
X384393Y-214564D01*
X385193Y-214297D01*
X385893Y-214564D01*
X386393Y-215097D01*
X386793Y-215897D01*
X386893Y-216831D01*
X386793Y-217631D01*
X386393Y-218431D01*
X385793Y-219097D01*
X385093Y-219364D01*
X384293Y-219097D01*
X383593Y-218298D01*
X383193Y-217097D01*
X383093Y-215764D01*
X383293Y-214031D01*
X383593Y-213097D01*
X384093Y-212164D01*
X384793Y-211497D01*
X385493Y-211364D01*
X386193Y-211631D01*
X386693Y-212297D01*
G01X390393Y-219364D02*
Y-211364D01*
X392993Y-218031D01*
X395593Y-211364D01*
Y-219364D01*
G01X400993Y-211364D02*
Y-219364D01*
G01X398693Y-211364D02*
X403293D01*
G01X406893Y-219364D02*
Y-211364D01*
G01X411093D02*
Y-219364D01*
G01Y-215364D02*
X406893D01*
G01X414793Y-217764D02*
X415393Y-218697D01*
X416193Y-219231D01*
X417093Y-219364D01*
X417893Y-219231D01*
X418693Y-218564D01*
X419193Y-217764D01*
X419293Y-216964D01*
X419093Y-216031D01*
X418393Y-215364D01*
X417693Y-215097D01*
X416793D01*
G01X417693D02*
X418293Y-214697D01*
X418793Y-214031D01*
X418993Y-213231D01*
X418793Y-212431D01*
X418293Y-211764D01*
X417393Y-211364D01*
X416493Y-211497D01*
X415593Y-212031D01*
G01X422493Y-219364D02*
X424993Y-211364D01*
X427493Y-219364D01*
G01X426593Y-216564D02*
X423393D01*
G01X430793Y-219364D02*
Y-211364D01*
X432793D01*
X433593Y-211764D01*
X434193Y-212297D01*
X434693Y-213097D01*
X435093Y-214031D01*
X435193Y-215364D01*
X435093Y-216697D01*
X434693Y-217631D01*
X434193Y-218431D01*
X433593Y-218964D01*
X432793Y-219364D01*
X430793D01*
G01X440993Y-211364D02*
X440193Y-211631D01*
X439593Y-212297D01*
X439193Y-213097D01*
X438893Y-214164D01*
X438793Y-215364D01*
X438893Y-216564D01*
X439193Y-217631D01*
X439593Y-218431D01*
X440193Y-219097D01*
X440993Y-219364D01*
X441793Y-219097D01*
X442393Y-218431D01*
X442793Y-217631D01*
X443093Y-216564D01*
X443193Y-215364D01*
X443093Y-214164D01*
X442793Y-213097D01*
X442393Y-212297D01*
X441793Y-211631D01*
X440993Y-211364D01*
G01X380993Y-186364D02*
Y-194364D01*
G01X378693Y-186364D02*
X383293D01*
G01X387093Y-191031D02*
X387793Y-190097D01*
X388393Y-189564D01*
X389193Y-189297D01*
X389893Y-189564D01*
X390393Y-190097D01*
X390793Y-190897D01*
X390893Y-191831D01*
X390793Y-192631D01*
X390393Y-193431D01*
X389793Y-194097D01*
X389093Y-194364D01*
X388293Y-194097D01*
X387593Y-193298D01*
X387193Y-192097D01*
X387093Y-190764D01*
X387293Y-189031D01*
X387593Y-188097D01*
X388093Y-187164D01*
X388793Y-186497D01*
X389493Y-186364D01*
X390193Y-186631D01*
X390693Y-187297D01*
G01X394393Y-194364D02*
Y-186364D01*
X396993Y-193031D01*
X399593Y-186364D01*
Y-194364D01*
G01X401993Y-197031D02*
X407993D01*
G01X415193Y-187031D02*
X414593Y-186631D01*
X413893Y-186364D01*
X413093D01*
X412193Y-186764D01*
X411493Y-187431D01*
X410993Y-188231D01*
X410593Y-189564D01*
X410493Y-190764D01*
X410693Y-191964D01*
X410993Y-192764D01*
X411593Y-193564D01*
X412293Y-194097D01*
X412993Y-194364D01*
X413693D01*
X414393Y-194097D01*
X414993Y-193697D01*
X415493Y-193164D01*
G01X418393Y-194364D02*
Y-186364D01*
X420993Y-193031D01*
X423593Y-186364D01*
Y-194364D01*
G01X425993Y-197031D02*
X431993D01*
G01X434793Y-194364D02*
Y-186364D01*
X436793D01*
X437593Y-186764D01*
X438193Y-187297D01*
X438693Y-188097D01*
X439093Y-189031D01*
X439193Y-190364D01*
X439093Y-191697D01*
X438693Y-192631D01*
X438193Y-193431D01*
X437593Y-193964D01*
X436793Y-194364D01*
X434793D01*
G01X473793Y-244364D02*
Y-236364D01*
X475793D01*
X476593Y-236764D01*
X477193Y-237297D01*
X477693Y-238097D01*
X478093Y-239031D01*
X478193Y-240364D01*
X478093Y-241697D01*
X477693Y-242631D01*
X477193Y-243431D01*
X476593Y-243964D01*
X475793Y-244364D01*
X473793D01*
G01X503493D02*
Y-236364D01*
X502293Y-237964D01*
G01Y-244364D02*
X504693D01*
G01X509593Y-241031D02*
X510293Y-240097D01*
X510893Y-239564D01*
X511693Y-239297D01*
X512393Y-239564D01*
X512893Y-240097D01*
X513293Y-240897D01*
X513393Y-241831D01*
X513293Y-242631D01*
X512893Y-243431D01*
X512293Y-244097D01*
X511593Y-244364D01*
X510793Y-244097D01*
X510093Y-243298D01*
X509693Y-242097D01*
X509593Y-240764D01*
X509793Y-239031D01*
X510093Y-238097D01*
X510593Y-237164D01*
X511293Y-236497D01*
X511993Y-236364D01*
X512693Y-236631D01*
X513193Y-237297D01*
G54D11*
X23628Y321764D03*
Y338300D03*
G54D21*
G01X246224Y559284D02*
X247814Y560874D01*
Y563104D01*
X235057Y575861D01*
X221961D01*
X215204Y582618D01*
X204178D01*
X203940Y582380D01*
X198089D01*
X194709Y585760D01*
X171300D01*
X166879Y581339D01*
X165530D01*
X163053Y578862D01*
X158850D01*
X155465Y575472D01*
X148340D01*
X142801Y569933D01*
X126672Y553815D01*
X126381Y553526D01*
X70796D01*
X61872Y544602D01*
X46162D01*
X43780Y542220D01*
Y537580D01*
X30820Y524620D01*
Y382411D01*
X72550Y340681D01*
Y332842D01*
X71950Y332242D01*
X70200D01*
X69600Y332842D01*
Y339883D01*
X68736Y340747D01*
X67514D01*
X66650Y339883D01*
Y316584D01*
X86360Y296874D01*
Y255651D01*
X83600Y252891D01*
Y241157D01*
X85770Y238987D01*
Y232414D01*
X76769Y223413D01*
X73529D01*
X70660Y220544D01*
Y211820D01*
X68930Y210090D01*
Y197193D01*
G01X76030Y156152D02*
X69851D01*
X61570Y164433D01*
Y221678D01*
X67603Y227711D01*
Y285224D01*
X59690Y293137D01*
Y344566D01*
X45460Y358796D01*
Y358958D01*
X23800Y380609D01*
Y537725D01*
X38434Y552359D01*
X46582D01*
X48570Y554347D01*
X61040D01*
X65486Y558793D01*
X75710D01*
X79400Y562483D01*
X82860D01*
X83870Y561473D01*
X86451D01*
X87940Y559984D01*
X118453D01*
X140869Y582400D01*
X149851D01*
X161920Y594469D01*
X195334D01*
X196238Y593565D01*
X214275D01*
X220234Y587606D01*
X235057D01*
X245860Y576803D01*
Y575049D01*
G01X81165Y257717D02*
X70700D01*
X69900Y258517D01*
Y264382D01*
X70700Y265182D01*
X76208D01*
X77072Y266046D01*
Y267268D01*
X76208Y268132D01*
X70970D01*
X70170Y268932D01*
Y270282D01*
X70970Y271082D01*
X82250D01*
X83050Y271882D01*
Y273232D01*
X82250Y274032D01*
X70150D01*
X69660Y274522D01*
Y278199D01*
X70524Y279063D01*
X74756D01*
X75620Y279927D01*
Y281149D01*
X74756Y282013D01*
X70524D01*
X69660Y282877D01*
Y286081D01*
X67789Y287952D01*
Y289174D01*
X71566Y292951D01*
Y294172D01*
X70700Y295038D01*
X69480D01*
X65702Y291259D01*
X64482D01*
X61750Y293991D01*
Y298621D01*
X62614Y299485D01*
X72970D01*
X73770Y300285D01*
Y301635D01*
X72970Y302435D01*
X62614D01*
X61750Y303299D01*
Y304521D01*
X62614Y305385D01*
X67080D01*
X67880Y306185D01*
Y307535D01*
X67080Y308335D01*
X62614D01*
X61750Y309199D01*
Y345406D01*
X47510Y359646D01*
Y359808D01*
X25850Y381468D01*
Y536875D01*
X39283Y550308D01*
X47440D01*
X47680Y550548D01*
Y550557D01*
X49420Y552297D01*
X61894D01*
X66340Y556743D01*
X77856D01*
X79700Y558587D01*
X85730D01*
X86920Y557397D01*
X118772D01*
X141287Y579912D01*
X150657D01*
X154750Y584005D01*
Y584030D01*
X155760Y585040D01*
X155785D01*
X156438Y585693D01*
X156652D01*
X158970Y588011D01*
Y588619D01*
X162770Y592419D01*
X193183D01*
X194140Y591462D01*
X203947D01*
X205875Y589534D01*
X214992D01*
X219110Y585416D01*
X231446D01*
X242844Y574018D01*
X243209D01*
G01X246224Y556134D02*
X245454Y556904D01*
X243206D01*
X241013Y559097D01*
Y562900D01*
X233005Y570908D01*
X219593D01*
X215687Y574814D01*
X197076D01*
X193922Y577968D01*
X177881D01*
X176435Y576522D01*
X174070D01*
X171510Y573962D01*
X160890D01*
X157506Y570572D01*
X150378D01*
X128271Y548469D01*
X75881D01*
X66096Y538684D01*
X52778D01*
X35720Y521626D01*
Y384441D01*
X77630Y342531D01*
Y332572D01*
X78340Y331862D01*
Y318972D01*
X77476Y318108D01*
X76254D01*
X75390Y318972D01*
Y324695D01*
X74490Y325595D01*
X73340D01*
X72440Y324695D01*
Y317724D01*
X91270Y298894D01*
Y230463D01*
X80822Y220015D01*
Y205206D01*
X80022Y204406D01*
X77400D01*
X76600Y205206D01*
Y213512D01*
X75560Y214552D01*
Y218513D01*
G01X71510Y164548D02*
X72730Y165768D01*
Y199881D01*
X71530Y201081D01*
Y209088D01*
X73110Y210668D01*
Y219529D01*
X74544Y220963D01*
X78001D01*
X88330Y231292D01*
Y240548D01*
X86410Y242468D01*
Y245763D01*
X88820Y248173D01*
Y297879D01*
X69370Y317329D01*
Y325999D01*
X75080Y331709D01*
Y341616D01*
X33270Y383426D01*
Y522952D01*
X52095Y541777D01*
X65669D01*
X74562Y550670D01*
X74969Y551076D01*
X127405D01*
X127697Y551365D01*
X148932Y572595D01*
X149360Y573022D01*
X156484D01*
X159870Y576412D01*
X170486D01*
X173050Y578972D01*
X173094D01*
X175382Y581260D01*
X178809D01*
X180599Y583050D01*
X193915D01*
X197858Y579107D01*
X214947D01*
X220696Y573358D01*
X234090D01*
X245014Y562434D01*
X246224D01*
G01X125050Y384546D02*
Y325839D01*
X121435Y322224D01*
Y277919D01*
X123510Y275844D01*
Y160548D01*
X72260Y109298D01*
Y56903D01*
X48165Y32808D01*
Y21010D01*
X51580Y17595D01*
G01X122120Y386736D02*
Y325672D01*
X119480Y323032D01*
Y277111D01*
X119485D01*
X122460Y274136D01*
Y162559D01*
X70090Y110189D01*
Y57792D01*
X46240Y33942D01*
Y25548D01*
X42210Y21518D01*
X42205D01*
G01X104550Y262359D02*
X102413D01*
X96430Y268342D01*
Y304152D01*
X83380Y317202D01*
Y344892D01*
X40088Y388184D01*
Y518473D01*
X47809Y526194D01*
X54127D01*
X59339Y531406D01*
X85055D01*
X87800Y528661D01*
X115709D01*
X153760Y566712D01*
X173362D01*
X173660Y567010D01*
Y570304D01*
X174670Y571314D01*
X175907D01*
X178030Y573437D01*
X185395D01*
X193296Y565536D01*
X200233D01*
X203821Y569124D01*
X215415D01*
X218950Y565589D01*
G01X210790Y566926D02*
X205132D01*
X201630Y563424D01*
X191807D01*
X183844Y571387D01*
X178880D01*
X177660Y570167D01*
Y568104D01*
X174218Y564662D01*
X154615D01*
X116175Y526222D01*
X83700D01*
X80566Y529356D01*
X60276D01*
X55002Y524082D01*
X48684D01*
X42200Y517598D01*
Y389059D01*
X85500Y345759D01*
Y318069D01*
X98550Y305019D01*
Y269122D01*
X102010Y265662D01*
X104270D01*
G01X56610Y20553D02*
X56959D01*
X96349Y59943D01*
X108366D01*
X118723Y70300D01*
X253793D01*
X263720Y66574D01*
X388760D01*
X390603Y64731D01*
X398121D01*
X399422Y63430D01*
X402527D01*
X404310Y65213D01*
G01X54800Y25547D02*
X90422Y61169D01*
X106829D01*
X117010Y71350D01*
X253994D01*
X263920Y67624D01*
X389330D01*
X390898Y66056D01*
X400319D01*
X401220Y65155D01*
G01X68630Y599945D02*
X69936Y598639D01*
X76050D01*
X79150Y601739D01*
Y653936D01*
X89385Y664171D01*
X128190D01*
X131470Y660891D01*
X146327D01*
X150677Y665241D01*
X153640D01*
X155811Y667412D01*
X164651D01*
X167095Y669856D01*
X168525D01*
X169994Y668387D01*
X209852D01*
X212635Y665604D01*
G01X126300Y390369D02*
X122995D01*
X120170Y387544D01*
Y326480D01*
X117530Y323840D01*
Y276011D01*
X120475Y273066D01*
Y166188D01*
X80815Y126528D01*
X76880D01*
G01X82031Y523928D02*
X104350Y501609D01*
Y482477D01*
X112400Y474427D01*
X143350D01*
X144709Y475786D01*
X157581D01*
X160297Y473070D01*
X173782D01*
X177950Y468902D01*
X184790D01*
X198708Y454984D01*
X323080D01*
X325201Y457105D01*
X329275D01*
X333407Y461237D01*
X374363D01*
X398608Y436992D01*
X469322D01*
X470825Y435489D01*
X472255D01*
X473270Y436504D01*
Y437307D01*
X505208Y469245D01*
Y475491D01*
X512150Y482433D01*
X524785D01*
X524920Y482298D01*
X527321D01*
X529021Y480598D01*
X542856D01*
X544160Y479294D01*
X583127D01*
X602929Y459492D01*
X609899D01*
X610815Y460408D01*
X617980D01*
G01X87721Y505817D02*
X89276D01*
X102400Y492693D01*
Y481382D01*
X111596Y472186D01*
X114877D01*
X116799Y470264D01*
X123619D01*
X125832Y472477D01*
X144160D01*
Y472478D01*
X144526Y472844D01*
X144533D01*
X145525Y473836D01*
X146955D01*
X148314Y472477D01*
X158123D01*
X159480Y471120D01*
X172972D01*
X177140Y466952D01*
X181987D01*
X193947Y454992D01*
Y452402D01*
X199324Y447025D01*
X203518D01*
X209279Y452786D01*
X323649D01*
X326018Y455155D01*
X330088D01*
X334220Y459287D01*
X373553D01*
X397798Y435042D01*
X468507D01*
X470010Y433539D01*
X481794D01*
X491409Y443154D01*
X509902D01*
X512152Y445404D01*
X526514D01*
X529320Y442598D01*
X530760D01*
X531351Y443189D01*
X537896D01*
X539426Y444719D01*
X543530D01*
X548242Y449431D01*
X575615D01*
X583985Y457801D01*
X601861D01*
X602576Y457086D01*
X609510D01*
X610010Y456586D01*
Y456581D01*
G01X651840Y460012D02*
X651808Y460044D01*
X622117D01*
X619803Y462358D01*
X609762D01*
X608846Y461442D01*
X604264D01*
X584462Y481244D01*
X544974D01*
X543670Y482548D01*
X529994D01*
X526794Y485748D01*
X512689D01*
X503250Y476309D01*
Y471211D01*
X476173Y444134D01*
X474334D01*
X469142Y438942D01*
X401683D01*
X379190Y461435D01*
Y462436D01*
X374403Y467223D01*
X366380D01*
X365346Y468257D01*
X337664D01*
X328462Y459055D01*
X320599D01*
X318502Y456958D01*
X199498D01*
X185604Y470852D01*
X178760D01*
X174592Y475020D01*
X161112D01*
X158394Y477738D01*
X142980D01*
X141619Y476377D01*
X113208D01*
X108460Y481125D01*
Y484136D01*
X106301Y486295D01*
Y503855D01*
X109972Y507526D01*
Y509321D01*
G01X108026Y492500D02*
Y490746D01*
X108020D01*
Y486066D01*
X109510Y484576D01*
Y481560D01*
X113245Y477825D01*
X128347D01*
X130349Y479827D01*
X171272D01*
X179197Y471902D01*
X186044D01*
X199938Y458008D01*
X317452D01*
X319549Y460105D01*
X328020D01*
X337222Y469307D01*
X365786D01*
X366820Y468273D01*
X375818D01*
X380360Y463731D01*
Y461750D01*
X399718Y442392D01*
X419813D01*
X422140Y440065D01*
X468771D01*
X496992Y468286D01*
X498840D01*
X501100Y470546D01*
Y476612D01*
X512065Y487577D01*
X527091D01*
X531070Y483598D01*
X544106D01*
X545410Y482294D01*
X586673D01*
X605800Y463167D01*
G01X125480Y91163D02*
X126513Y90130D01*
X139816D01*
X142877Y87069D01*
X150770D01*
X156146Y84645D01*
X160632Y80159D01*
X413896D01*
X434330Y100593D01*
Y102868D01*
X447570Y116108D01*
Y125195D01*
X451698Y129323D01*
X456034D01*
X483420Y156709D01*
Y163766D01*
X487262Y167608D01*
X491847D01*
X501040Y176801D01*
Y177297D01*
G01X132400Y88153D02*
Y87744D01*
X134849Y85295D01*
X138827D01*
X160143Y77358D01*
X160991Y76510D01*
X251513D01*
X264494Y71636D01*
X378530D01*
X391299Y73389D01*
X392714Y74804D01*
X405392D01*
X406900Y73296D01*
X416085D01*
X437580Y94791D01*
Y101586D01*
X454905Y118911D01*
X478520D01*
X485810Y121595D01*
X495001D01*
X497430Y124024D01*
G01X129580Y86837D02*
X133262Y83155D01*
X140480D01*
X159610Y75908D01*
X160195Y75323D01*
X160407D01*
X160470Y75260D01*
X251275D01*
X263796Y70560D01*
X264260Y70386D01*
X264425Y70324D01*
X378168D01*
X384511Y71194D01*
X396929D01*
X397070Y71335D01*
X398510D01*
X401330Y70729D01*
X404823Y70525D01*
X416406Y71766D01*
X438890Y94250D01*
Y100535D01*
X455808Y117453D01*
X481180D01*
X487020Y119754D01*
G01X494210Y175035D02*
X492427Y173252D01*
X491600Y172797D01*
X490010Y171529D01*
X488360D01*
X481762Y164931D01*
X481034Y162308D01*
X479971Y156045D01*
X474541Y150615D01*
X474376D01*
X465035Y144234D01*
X443408Y127791D01*
X439911Y124294D01*
X439130Y122669D01*
Y119773D01*
X427270Y96236D01*
X412940Y81906D01*
X160945D01*
X156975Y85876D01*
X156951D01*
X155640Y86467D01*
X152970Y87671D01*
X151090Y88519D01*
X143482D01*
X139805Y92196D01*
X130164D01*
X129780Y92580D01*
G01X498940Y179744D02*
X498652D01*
X496300Y177392D01*
X493808D01*
X489777Y173361D01*
X488132D01*
X478520Y163749D01*
Y156645D01*
X473923Y152067D01*
X446044Y133022D01*
X437680Y124663D01*
Y120268D01*
X425820Y104681D01*
Y97508D01*
X411668Y83356D01*
X162501D01*
X155146Y90711D01*
X143783D01*
X141040Y93457D01*
X136606Y94643D01*
X124150D01*
G01X502999Y180541D02*
X500782Y181526D01*
X497391D01*
X490000Y178991D01*
X486309Y175959D01*
X476790Y164645D01*
Y157318D01*
X471945Y152473D01*
X444784Y133922D01*
X436230Y125368D01*
Y120757D01*
X424290Y105066D01*
Y98336D01*
X410760Y84806D01*
X163468D01*
X155948Y92326D01*
X144224D01*
X141792Y94758D01*
X128330Y98360D01*
G01X312972Y712693D02*
X310682Y710403D01*
X194644D01*
X191010Y706769D01*
Y700428D01*
X187350Y696768D01*
Y694559D01*
X161253Y668462D01*
X154760D01*
X152589Y666291D01*
X135865D01*
X132190Y662616D01*
G01X140350Y81347D02*
X145109Y76588D01*
X150483D01*
X154108Y72963D01*
X158766D01*
X159773Y73970D01*
X251151D01*
X264190Y69074D01*
X394081D01*
X395333Y67822D01*
X400218D01*
X401470Y69074D01*
X415493D01*
X440150Y93731D01*
Y99273D01*
X455912Y115035D01*
X523415D01*
X529781Y108669D01*
X532955D01*
G01X488220Y157515D02*
X485994D01*
X455943Y127464D01*
X451770D01*
X448820Y124514D01*
Y115590D01*
X435580Y102350D01*
Y99206D01*
X414966Y78592D01*
X160425D01*
X155420Y83597D01*
X150497Y85819D01*
X142150D01*
X140305Y87664D01*
X135290D01*
G01X609370Y452974D02*
X605039D01*
X604210Y453803D01*
X588060D01*
X575526Y441269D01*
X536940D01*
X536070Y442139D01*
X534630D01*
X530982Y438491D01*
X527067D01*
X524560Y440998D01*
X523120D01*
X522532Y441586D01*
X498944D01*
X498540Y441990D01*
X493463D01*
X482935Y431462D01*
X399887D01*
X373112Y458237D01*
X335343D01*
X331211Y454105D01*
X326459D01*
X324090Y451736D01*
X209722D01*
X203961Y445975D01*
X198889D01*
X192890Y451974D01*
Y454555D01*
X181543Y465902D01*
X176700D01*
X172532Y470070D01*
X159040D01*
X157929Y471181D01*
X149235D01*
X147390Y469336D01*
X136192D01*
X135300Y468444D01*
G01X164550Y61239D02*
X166076Y59713D01*
X169110D01*
X170066Y60669D01*
X251113D01*
X252290Y59492D01*
X358114D01*
X359921Y57685D01*
X461829D01*
X469847Y65703D01*
X486554D01*
X489554Y62700D01*
X511400D01*
X512800Y61300D01*
X617300D01*
X637090Y81090D01*
Y186551D01*
X647119Y196580D01*
Y262819D01*
X721865Y337565D01*
Y479048D01*
X720855Y480058D01*
X718398D01*
X717512Y479172D01*
X711285D01*
X710671Y479786D01*
G01X168040Y61462D02*
X169197Y62619D01*
X251930D01*
X253107Y61442D01*
X345785D01*
X347572Y63229D01*
X364454D01*
X365435Y62248D01*
X374280D01*
X374748Y62716D01*
X382230D01*
X382530Y62416D01*
X392173D01*
X394954Y59635D01*
X461012D01*
X471177Y69800D01*
X526126D01*
X531526Y64400D01*
X616100D01*
X633370Y81670D01*
Y188019D01*
X644119Y198768D01*
Y264119D01*
X704545Y324545D01*
Y417345D01*
X677070Y444820D01*
G01X648920Y457851D02*
X642158D01*
X642148Y457861D01*
X624424D01*
X617587Y451024D01*
X604224D01*
X603395Y451853D01*
X588872D01*
X573560Y436541D01*
X520379D01*
X519206Y437714D01*
X503946D01*
X503210Y438450D01*
X492941D01*
X484003Y429512D01*
X399076D01*
X372301Y456287D01*
X345101D01*
X340969Y452155D01*
X327270D01*
X324901Y449786D01*
X210532D01*
X204771Y444025D01*
X198081D01*
X190940Y451166D01*
Y453747D01*
X180735Y463952D01*
X175468D01*
X171616Y467804D01*
G01X190375Y695624D02*
X193381D01*
X195656Y697899D01*
X197243D01*
G01X191150Y724108D02*
Y722309D01*
X199039Y714420D01*
X202509D01*
X204419Y712510D01*
X205440D01*
G01X337030Y677894D02*
X334124D01*
X330496Y674266D01*
X325380D01*
X309970Y658856D01*
Y655213D01*
X305215Y650458D01*
X296311D01*
X286745Y660024D01*
Y699701D01*
X279628Y706818D01*
X273852D01*
X270890Y703856D01*
X260333D01*
X259890Y703413D01*
X252972D01*
X251510Y704875D01*
X239262D01*
X236835Y702448D01*
X235405D01*
X232047Y705806D01*
X199914D01*
X197582Y703474D01*
G01X200692Y704081D02*
X228338D01*
X232013Y700406D01*
X266020D01*
X268019Y702405D01*
X281990D01*
X285210Y699185D01*
Y659508D01*
X295710Y649008D01*
X305816D01*
X321444Y664636D01*
Y666098D01*
X325676Y670330D01*
X331234D01*
X335915Y675011D01*
G01X197243Y697899D02*
X204755D01*
X207068Y695586D01*
X211236D01*
G01D02*
X217929Y702279D01*
X228087D01*
X232971Y697395D01*
X233954D01*
G01X205883Y724373D02*
Y723038D01*
X211891Y717030D01*
X220550D01*
X220890Y716690D01*
X238327D01*
X242680Y712337D01*
G01X200817Y724180D02*
Y722657D01*
X207834Y715640D01*
X212639D01*
X216055Y712224D01*
X217485D01*
X220692Y715431D01*
X227896D01*
X229263Y714064D01*
X234960D01*
G01X211897Y723870D02*
X213806D01*
X218932Y718744D01*
X220330D01*
X221246Y717828D01*
X248410D01*
X252119Y714119D01*
X259549D01*
X260680Y712988D01*
G01X239084Y696252D02*
X240297Y697465D01*
X251451D01*
G01X233954Y697395D02*
X237944D01*
X239084Y696255D01*
Y696252D01*
G01X718431Y483368D02*
X719379Y482420D01*
X721251D01*
X733295Y470376D01*
Y346095D01*
X649070Y261870D01*
Y195532D01*
X641040Y187502D01*
Y82240D01*
X618100Y59300D01*
X508500D01*
X507300Y60500D01*
X499122D01*
X497100Y58478D01*
X479167D01*
X426559Y5870D01*
X279339D01*
X268809Y16400D01*
G01X272967Y325842D02*
X273218D01*
X274843Y327467D01*
X275990D01*
X278892Y330369D01*
X283516D01*
X289303Y336156D01*
X290760D01*
X299830Y345226D01*
Y345611D01*
X313674Y359455D01*
X322934D01*
X325738Y356651D01*
X327813D01*
X330505Y359343D01*
X341796D01*
X347014Y364561D01*
X349541D01*
X352680Y367700D01*
X364999D01*
X381800Y350899D01*
X533056D01*
X592370Y410213D01*
Y418061D01*
X613907Y439598D01*
X643360D01*
X654890Y451128D01*
Y482324D01*
X666941Y494375D01*
X678900D01*
X688566Y504041D01*
X700829D01*
G01X327058Y358381D02*
Y358384D01*
X324612Y360830D01*
X313099D01*
X298310Y346041D01*
Y345191D01*
X291175Y338056D01*
X290000D01*
X283163Y331219D01*
X278539D01*
X276364Y329044D01*
X271789D01*
X270293Y330540D01*
G01X651080Y455238D02*
Y454576D01*
X644500Y447996D01*
Y443708D01*
X642498Y441706D01*
X613045D01*
X590270Y418931D01*
Y411088D01*
X532181Y352999D01*
X384141D01*
X367340Y369800D01*
X351014D01*
X347875Y366661D01*
X345520D01*
X341095Y362236D01*
X312550D01*
X295679Y345365D01*
X293556D01*
X290909Y342718D01*
Y340168D01*
X282810Y332069D01*
X274364D01*
X272964Y330669D01*
G01X458120Y44721D02*
Y44720D01*
X420320Y6920D01*
X281813D01*
X278660Y10073D01*
G01X278067Y325842D02*
Y326550D01*
X279984Y328467D01*
X284489D01*
X285397Y327559D01*
X286745D01*
X292751Y333565D01*
X296120D01*
X304701Y342146D01*
X306820D01*
G01X323040Y354485D02*
X321520Y356005D01*
X320430D01*
X320270Y356165D01*
X311869D01*
X301540Y345836D01*
Y341135D01*
X298551Y338146D01*
X294899D01*
X290553Y333800D01*
X288388D01*
X284095Y329507D01*
X279433D01*
X275768Y325842D01*
X275517D01*
G01X285794Y339063D02*
Y340250D01*
X292019Y346475D01*
X295301D01*
X312559Y363733D01*
X338489D01*
X343828Y369072D01*
X347060D01*
Y369075D01*
X349787Y371802D01*
X366828D01*
X384581Y354049D01*
X531679D01*
X589070Y411440D01*
Y423525D01*
G01X652110Y465238D02*
X648718Y461846D01*
X638202D01*
X636185Y463863D01*
X632930D01*
X627971Y468822D01*
X601635D01*
X584480Y485977D01*
X541874D01*
X540545Y484648D01*
X531510D01*
X527531Y488627D01*
X511630D01*
X496394Y473391D01*
Y469253D01*
X469726Y442585D01*
X432608D01*
X431379Y443814D01*
X421309D01*
X418432Y446691D01*
X396910D01*
X381410Y462191D01*
Y464166D01*
X376253Y469323D01*
X367260D01*
X366226Y470357D01*
X335794D01*
X326895Y461458D01*
X299320D01*
X298624Y460762D01*
X280210D01*
G01X628250Y471142D02*
X602075D01*
X585290Y487927D01*
X540730D01*
X539401Y486598D01*
X532320D01*
X528341Y490577D01*
X510822D01*
X491064Y470819D01*
Y466681D01*
X468918Y444535D01*
X434867D01*
X431847Y447555D01*
X420326D01*
X419240Y448641D01*
X397721D01*
X385650Y460712D01*
Y465200D01*
X379577Y471273D01*
X368070D01*
X367036Y472307D01*
X334876D01*
X325977Y463408D01*
X298505D01*
X298233Y463136D01*
X284528D01*
X280380Y467284D01*
G01X278990Y464793D02*
X278430Y465353D01*
Y468092D01*
X279572Y469234D01*
X282519D01*
X286667Y465086D01*
X295880D01*
X296178Y465384D01*
X324169D01*
X334518Y475733D01*
X341370D01*
X345520Y479883D01*
Y512113D01*
X348550Y515143D01*
Y520549D01*
X354890Y526889D01*
Y542948D01*
X372060Y560118D01*
X373287D01*
X384513Y571344D01*
X447845D01*
X455116Y564073D01*
X457862D01*
X462920Y559015D01*
Y556269D01*
X478340Y540849D01*
X489962D01*
G01X297073Y329159D02*
Y332145D01*
X302200Y337272D01*
X306551D01*
X317769Y348490D01*
X320795D01*
X323316Y351011D01*
X342162D01*
X348882Y357731D01*
X359508D01*
X373425Y343814D01*
X535201D01*
X584148Y392761D01*
X594973D01*
X598250Y396038D01*
Y415585D01*
X616094Y433429D01*
X652615D01*
X662780Y443594D01*
Y477039D01*
G01X641690Y443656D02*
X606443D01*
X587120Y424333D01*
Y412256D01*
X530863Y355999D01*
X385391D01*
X367638Y373752D01*
X348973D01*
X346243Y371022D01*
X343020D01*
X337684Y365686D01*
X311682D01*
X305446Y359450D01*
G01X292970Y682450D02*
X301989Y673431D01*
X309425D01*
X324857Y688863D01*
X334350D01*
X335455Y689968D01*
X347865D01*
X354750Y696853D01*
X362552D01*
X362798Y696607D01*
X376489D01*
X377100Y697218D01*
G01X297770Y674720D02*
X303059Y669431D01*
X308720D01*
X326836Y687547D01*
X334978D01*
X335954Y688523D01*
X350153D01*
X352583Y690953D01*
X364351D01*
X366781Y688523D01*
X371199D01*
X372661Y689985D01*
X376946D01*
G01X303681Y714421D02*
X311456Y722196D01*
X315138D01*
X319702Y726760D01*
X335360D01*
X335597Y726523D01*
X345564D01*
X351680Y720407D01*
X358909D01*
X361430Y717886D01*
X381652D01*
X382432Y717106D01*
X395156D01*
X396983Y715279D01*
X404982D01*
X407021Y717318D01*
X407751D01*
X412350Y721917D01*
Y722044D01*
X413365Y723059D01*
X414800D01*
X415782Y722077D01*
X426722D01*
X427384Y722739D01*
X430211D01*
X432582Y720368D01*
X439327D01*
X441935Y717760D01*
X475340D01*
X476343Y716757D01*
X499717D01*
X507856Y708618D01*
X530012D01*
G01X675100Y749300D02*
X677250Y747150D01*
Y742950D01*
X673099Y738799D01*
X645700D01*
X643799Y740700D01*
X637500D01*
X636058Y739258D01*
X529577D01*
X526301Y735982D01*
Y732512D01*
X525291Y731502D01*
X524489D01*
X516630Y723643D01*
Y723409D01*
X513168Y719947D01*
X502500D01*
X501151Y721296D01*
X485494D01*
X484234Y720036D01*
X444544D01*
X443370Y721210D01*
X443122D01*
X437897Y726435D01*
X414407D01*
X410700Y722728D01*
Y722601D01*
X407067Y718968D01*
X405587D01*
X403548Y716929D01*
X397673D01*
X395846Y718756D01*
X383117D01*
X379840Y722033D01*
X371390D01*
X371254Y721897D01*
X362618D01*
X361932Y722583D01*
X355136D01*
X349546Y728173D01*
X336287D01*
X336050Y728410D01*
X307236D01*
X296885Y718059D01*
G01X672710Y746235D02*
Y746210D01*
X667629Y741129D01*
X648871D01*
X646600Y743400D01*
X635900D01*
X634700Y742200D01*
Y742129D01*
X633700Y741129D01*
X519925D01*
X506165Y727369D01*
X499540D01*
X498824Y728085D01*
X413723D01*
X408450Y722812D01*
Y722685D01*
X407435Y721670D01*
X405702D01*
X402611Y718579D01*
X398363D01*
X396536Y720406D01*
X384267D01*
X378560Y726113D01*
X377120D01*
X376741Y725734D01*
X354840D01*
X350751Y729823D01*
X336977D01*
X336740Y730060D01*
X301183D01*
X295160Y724037D01*
Y717344D01*
X296981Y715523D01*
X297223D01*
G01X291318Y713875D02*
X291575Y714132D01*
Y725615D01*
X297670Y731710D01*
X337430D01*
X337667Y731473D01*
X356158D01*
X358537Y729094D01*
X363578D01*
X364030Y729546D01*
X377467D01*
X381862Y725151D01*
X395087D01*
X400009Y720229D01*
X401445D01*
X402460Y721244D01*
Y722315D01*
X411101Y730956D01*
X504097D01*
X515920Y742779D01*
X630800D01*
X631400Y743379D01*
Y743400D01*
X636400Y748400D01*
X647400D01*
X652500Y743300D01*
X666700D01*
X672500Y749100D01*
Y749179D01*
G01X594860Y395088D02*
X594424Y394652D01*
X584548D01*
X534760Y344864D01*
X373914D01*
X359997Y358781D01*
X348432D01*
X344690Y355039D01*
X339620D01*
X339133Y355526D01*
X332157D01*
X328936Y352305D01*
X315248D01*
X306820Y343877D01*
Y342146D01*
G01X631280Y446007D02*
X631160Y445887D01*
X591060D01*
X571426Y426253D01*
X526420D01*
X522820Y422653D01*
Y418529D01*
X518349Y414058D01*
X479325D01*
X470581Y422802D01*
X395566D01*
X375420Y442948D01*
Y446481D01*
X370566Y451335D01*
X357385D01*
X354268Y448218D01*
X353503D01*
X337786Y432501D01*
X328304D01*
X322803Y427000D01*
Y426763D01*
X320190Y424149D01*
X319514D01*
X317140Y421775D01*
G01X319478Y429389D02*
X320740Y430651D01*
Y433402D01*
X323870Y436532D01*
X337113D01*
X352840Y452259D01*
Y452277D01*
X353850Y453287D01*
X370626D01*
X371193Y452721D01*
X397402Y426512D01*
X469430D01*
X480809Y415133D01*
X516926D01*
X521020Y419227D01*
Y423924D01*
X524860Y427764D01*
X571447D01*
X590620Y446937D01*
X622939D01*
X626250Y450248D01*
G01X318950Y432473D02*
X319120Y432643D01*
Y433267D01*
X323435Y437582D01*
X336678D01*
X345487Y446391D01*
Y446409D01*
X353415Y454337D01*
X371067D01*
X397842Y427562D01*
X484813D01*
X491810Y434559D01*
X507775D01*
X508980Y435764D01*
X516500D01*
X517792Y434472D01*
X575159D01*
X589090Y448403D01*
X603446D01*
X603705Y448662D01*
X610580D01*
G01X469229Y638135D02*
Y638126D01*
X467309Y636206D01*
X462622D01*
X459345Y632929D01*
X441229D01*
X440410Y633748D01*
X430405D01*
X419193Y644960D01*
X403786D01*
X401316Y647430D01*
X385640D01*
X382641Y644431D01*
X374038D01*
X371472Y646997D01*
X322642D01*
X318630Y642985D01*
Y642680D01*
X311382Y635432D01*
G01X535062Y708679D02*
X533276Y706893D01*
X505974D01*
X500560Y712307D01*
X499120D01*
X499083Y712270D01*
X478784D01*
X474627Y716427D01*
X440514D01*
X439260Y717681D01*
X430128D01*
X427655Y720154D01*
X415640D01*
X412795Y717309D01*
X412605D01*
X411364Y716068D01*
X407539D01*
X405500Y714029D01*
X396463D01*
X394636Y715856D01*
X373163D01*
X372383Y716636D01*
X355617D01*
X353860Y718393D01*
X348914D01*
X344646Y722661D01*
X336745D01*
X335805Y721721D01*
X316538D01*
X314143Y719326D01*
X311275D01*
X307113Y715164D01*
Y713003D01*
G01X537503Y710088D02*
Y708680D01*
X534466Y705643D01*
X505298D01*
X502116Y708825D01*
X490619D01*
X490121Y708327D01*
X446839D01*
X438735Y716431D01*
X428135D01*
X427171Y715467D01*
X412539D01*
X411890Y714818D01*
X408259D01*
X406220Y712779D01*
X395943D01*
X394116Y714606D01*
X372643D01*
X371863Y715386D01*
X355097D01*
X353340Y717143D01*
X346576D01*
X345194Y718525D01*
X335490D01*
X334971Y718006D01*
X320462D01*
X320340Y718128D01*
X315137D01*
X311307Y714298D01*
X309531D01*
G01X540062Y708779D02*
X535476Y704193D01*
X447419D01*
X441330Y710282D01*
X437630D01*
X432931Y714981D01*
X428745D01*
X427781Y714017D01*
X419800D01*
X419151Y713368D01*
X408866D01*
X402699Y707201D01*
X394992D01*
X393061Y709132D01*
X387704D01*
X383680Y713156D01*
X372033D01*
X371890Y713299D01*
X369428D01*
X368065Y711936D01*
X363361D01*
X362205Y710780D01*
X357638D01*
X352725Y715693D01*
X351290D01*
X350672Y715075D01*
X330770D01*
X330093Y715752D01*
X322400D01*
X321326Y714678D01*
X314957D01*
X312972Y712693D01*
G01X545062Y708679D02*
X542402D01*
X536866Y703143D01*
X446979D01*
X440890Y709232D01*
X437194D01*
X432495Y713931D01*
X429510D01*
X428546Y712967D01*
X420240D01*
X416445Y709172D01*
X415287D01*
X415270Y709189D01*
X413830D01*
X408873Y704232D01*
X386032D01*
X382302Y707962D01*
X376950D01*
X376868Y707880D01*
X354270D01*
X353625Y708525D01*
X343811D01*
X342945Y707659D01*
X341515D01*
X338520Y710654D01*
X320282D01*
X318090Y712846D01*
G01X696494Y513677D02*
X679352Y496535D01*
X661751D01*
X653840Y488624D01*
Y455558D01*
X647363Y449081D01*
X647070D01*
X645555Y447566D01*
Y443278D01*
X642927Y440650D01*
X613474D01*
X591320Y418496D01*
Y410653D01*
X532616Y351949D01*
X382241D01*
X365440Y368750D01*
X352239D01*
X349100Y365611D01*
X346570D01*
X341690Y360731D01*
X329408D01*
X327058Y358381D01*
G01D02*
Y358376D01*
G01X323040Y354485D02*
X328148D01*
X331270Y357607D01*
X341731D01*
X346805Y362681D01*
X356834D01*
X360483Y366330D01*
X364185D01*
X380666Y349849D01*
X533491D01*
X593960Y410318D01*
Y418166D01*
X614340Y438546D01*
X648066D01*
X655940Y446420D01*
Y475945D01*
X673318Y493323D01*
X692551D01*
X702554Y503326D01*
Y504756D01*
X700031Y507279D01*
X696891D01*
G01X427210Y691934D02*
X428280Y690864D01*
Y688280D01*
X419800Y679800D01*
Y672043D01*
X412992Y665235D01*
X410695D01*
X409419Y663959D01*
X407286D01*
X398281Y654954D01*
X395650D01*
X391410Y650714D01*
X384891D01*
X382330Y648153D01*
X375220D01*
X374926Y648447D01*
X359226D01*
X356312Y651361D01*
X339986D01*
X333771Y657576D01*
X332055D01*
X326228Y663403D01*
X324255D01*
X323245Y664413D01*
Y665848D01*
X324250Y666853D01*
X327109D01*
X327500Y667244D01*
G01X421350Y694003D02*
Y694001D01*
X419460Y692111D01*
Y690564D01*
X418546Y689650D01*
Y674719D01*
X413350Y669523D01*
X410632D01*
X404170Y663061D01*
Y662868D01*
X397655Y656353D01*
X393947D01*
X389558Y651964D01*
X378777D01*
X377767Y650954D01*
X374810D01*
X372323Y653441D01*
X364265D01*
X363030Y654676D01*
X359845D01*
X357703Y656818D01*
X339414D01*
X336330Y659902D01*
X334836D01*
X329610Y665128D01*
X324970D01*
G01X335915Y675011D02*
X336619D01*
X340317Y678709D01*
X365040D01*
X365700Y679369D01*
X372074D01*
X373884Y681179D01*
X388554D01*
X389240Y680493D01*
X392569D01*
X398775Y686699D01*
X400968D01*
G01X333180Y665611D02*
X338301D01*
X339639Y666949D01*
X343019D01*
X344684Y665284D01*
X356953D01*
X360580Y661657D01*
X364587D01*
X364900Y661344D01*
X370535D01*
X372437Y659442D01*
X374088D01*
X377780Y655750D01*
X385561D01*
X408820Y679009D01*
Y692385D01*
X411678Y695243D01*
X416005D01*
X421935Y701173D01*
X426391D01*
G01X423242Y707949D02*
X416930Y701637D01*
Y701151D01*
X414627Y698848D01*
X413515D01*
X407570Y692903D01*
Y680335D01*
X389125Y661890D01*
X380894D01*
X380820Y661964D01*
X379380D01*
X378108Y660692D01*
X372960D01*
X369857Y663795D01*
X368420D01*
X365286Y666929D01*
X357932D01*
X356008Y668853D01*
X353180D01*
X352191Y667864D01*
X350737D01*
X349642Y668959D01*
X336915D01*
X335130Y670744D01*
G01X334313Y663113D02*
Y663116D01*
X334753Y663556D01*
X339650D01*
X340300Y662906D01*
X344432D01*
X345920Y661418D01*
X356948D01*
X358003Y660363D01*
X363641D01*
X364127Y659877D01*
X368485D01*
X375930Y652432D01*
X377365D01*
X378555Y653622D01*
X386128D01*
X395760Y663254D01*
X401656D01*
X409331Y670929D01*
X412390D01*
X417035Y675574D01*
Y689907D01*
X418210Y691082D01*
Y694544D01*
X422232Y698566D01*
X423642D01*
X425590Y696618D01*
Y695895D01*
G01X367066Y681094D02*
X365863Y682297D01*
X363930D01*
X363616Y682611D01*
X356583D01*
X355117Y681145D01*
X340281D01*
X337030Y677894D01*
G01X343880Y356989D02*
X347622Y360731D01*
X360810D01*
X374727Y346814D01*
X533942D01*
X596090Y408962D01*
Y417538D01*
X615143Y436591D01*
X653019D01*
X660740Y444312D01*
Y459951D01*
X657890Y462801D01*
Y475137D01*
X663301Y480548D01*
X674960D01*
X678135Y483723D01*
X683112D01*
G01X548470Y378127D02*
X534583Y364240D01*
X501572D01*
X495281Y357949D01*
X386201D01*
X365360Y378790D01*
X353098D01*
X350075Y375767D01*
X349110D01*
G01X341190Y712379D02*
X343305D01*
X344060Y711624D01*
X352585D01*
X354879Y709330D01*
X362821D01*
X362903Y709412D01*
X382908D01*
X384638Y707682D01*
X392455D01*
X394386Y705751D01*
X408092D01*
X413238Y710897D01*
X415730D01*
G01X715328Y481122D02*
Y496978D01*
X715703Y497353D01*
Y504613D01*
X705312Y515004D01*
X697933D01*
X697310Y515627D01*
X695681D01*
X695058Y515004D01*
X692713D01*
X682520Y504811D01*
Y503811D01*
X680421Y501712D01*
X666371D01*
X658240Y509843D01*
X641047D01*
X631847Y519043D01*
X586750D01*
X585642Y520151D01*
X490764D01*
X456579Y554336D01*
Y556198D01*
X454983Y557794D01*
X451860D01*
X444160Y565494D01*
X389411D01*
X388270Y566635D01*
Y567116D01*
X386539Y568847D01*
X384780D01*
X363604Y547671D01*
Y544997D01*
X368825Y539776D01*
G01X609070Y721917D02*
X604187Y726800D01*
X582873D01*
X582355Y726282D01*
X561680D01*
X560670Y725272D01*
Y725021D01*
X554625Y718976D01*
X552555D01*
X545817Y712238D01*
Y710801D01*
X546787Y709831D01*
Y707964D01*
X545777Y706954D01*
X542373D01*
X537391Y701972D01*
X497115D01*
X493074Y697931D01*
X489740D01*
X486533Y701138D01*
X447494D01*
X440450Y708182D01*
X436363D01*
X431664Y712881D01*
X430023D01*
X428916Y711774D01*
X421300D01*
X414330Y704804D01*
X412733D01*
X403750Y695821D01*
Y681692D01*
X391800Y669742D01*
X378127D01*
X376816Y668431D01*
X371901D01*
X368200Y672132D01*
G01X620670Y722216D02*
X620323Y722563D01*
X612156D01*
X609785Y720192D01*
X607443D01*
X602142Y725493D01*
X591725D01*
X589690Y723458D01*
Y723395D01*
X585346Y719051D01*
X577298D01*
X576819Y719530D01*
X572338D01*
X572331Y719523D01*
X561553D01*
X561260Y719816D01*
X559829D01*
X551729Y711716D01*
Y708844D01*
X548789Y705904D01*
X542814D01*
X537367Y700457D01*
X503676D01*
X500118Y696899D01*
X495238D01*
X494743Y696404D01*
X489777D01*
X486248Y699933D01*
X447206D01*
X440007Y707132D01*
X433195D01*
X431446Y708881D01*
X428171D01*
X426328Y710724D01*
X422075D01*
X415105Y703754D01*
X413168D01*
X405070Y695656D01*
Y681527D01*
X391747Y668204D01*
X378911D01*
X378088Y667381D01*
X368852D01*
X368100Y668133D01*
G01X399829Y690191D02*
X394044Y684406D01*
X373538D01*
X370226Y681094D01*
X367066D01*
G01X378910Y430874D02*
X379286D01*
X389008Y421152D01*
X469326D01*
X478223Y412255D01*
X519747D01*
X529699Y422207D01*
X530940D01*
G01X616070Y720838D02*
X612400D01*
X610704Y719142D01*
X604072D01*
X602200Y721015D01*
X589967D01*
X586351Y717399D01*
X579544D01*
X578225Y716080D01*
X572548D01*
X571356Y717272D01*
X563918D01*
X557050Y710404D01*
X554347D01*
X553337Y709394D01*
Y708967D01*
X549224Y704854D01*
X544240D01*
X538686Y699300D01*
X505377D01*
X495975Y689898D01*
X490383D01*
X481697Y698584D01*
X447067D01*
X440220Y705431D01*
X426736D01*
X425505Y706662D01*
Y708126D01*
X423957Y709674D01*
X422527D01*
X415557Y702704D01*
X413603D01*
X406120Y695221D01*
Y681092D01*
X388368Y663340D01*
X381504D01*
X381430Y663414D01*
X374677D01*
X373680Y662417D01*
G01X638350Y507893D02*
X629150Y517093D01*
X585763D01*
X584655Y518201D01*
X491577D01*
X491576Y518200D01*
X489950D01*
X489949Y518201D01*
X484361D01*
X459670Y542892D01*
Y548480D01*
X455639Y552511D01*
X452670D01*
X441637Y563544D01*
X400045D01*
X391483Y554982D01*
Y510089D01*
X398310Y503262D01*
X403887D01*
X405348Y504723D01*
Y506316D01*
G01X396520Y567444D02*
X446225D01*
X453925Y559744D01*
X455791D01*
X458530Y557005D01*
Y555143D01*
X481521Y532152D01*
X514188D01*
X521290Y525050D01*
X557663D01*
X562663Y530050D01*
X581759D01*
X588519Y523290D01*
X635250D01*
X640085Y518455D01*
X661423D01*
X666743Y513135D01*
Y511075D01*
X674156Y503662D01*
G01X393596Y567630D02*
X395360Y569394D01*
X447035D01*
X454735Y561694D01*
X456599D01*
X460480Y557813D01*
Y555951D01*
X482329Y534102D01*
X516121D01*
X523223Y527000D01*
X545353D01*
X552303Y533950D01*
X580620D01*
X589328Y525242D01*
X625438D01*
X626365Y526169D01*
X666269D01*
X675479Y516959D01*
X694248D01*
X694866Y517577D01*
X698120D01*
X698743Y516954D01*
X700719D01*
G01X401353Y624007D02*
X413147D01*
X415090Y625950D01*
X423331D01*
X428800Y631419D01*
X437256D01*
X438535Y632698D01*
X439970D01*
X440849Y631820D01*
X471280D01*
X475880Y627220D01*
X496270D01*
X497635Y625855D01*
X510853D01*
X514812Y621896D01*
X541204D01*
X541260Y621952D01*
X545413D01*
X545900Y621465D01*
X560455D01*
X564567Y625577D01*
X568598D01*
X569019Y625998D01*
X571650D01*
G01X410085Y618329D02*
X416341Y624585D01*
X424277D01*
X428940Y629248D01*
X439965D01*
X441487Y630770D01*
X470840D01*
X481195Y620415D01*
X538199D01*
X540112Y618502D01*
X560703D01*
X565800Y623599D01*
X572808D01*
X574730Y625521D01*
G01X444458Y669350D02*
X438150Y663042D01*
Y655333D01*
X436687Y653870D01*
X436152D01*
X430455Y648173D01*
Y646096D01*
X433912Y642639D01*
X434681D01*
G01X447210Y665143D02*
X447141D01*
X440260Y658262D01*
Y648540D01*
X437100Y645380D01*
Y643793D01*
G01X498350Y627580D02*
X496270Y629660D01*
X479142D01*
X473840Y634962D01*
Y638015D01*
X470526Y641329D01*
X468917D01*
X467104Y643142D01*
X463494D01*
X461982Y641630D01*
X445400D01*
X443300Y643730D01*
Y646980D01*
X448935Y652615D01*
Y665858D01*
X447161Y667632D01*
Y673564D01*
G01X458820Y674137D02*
X452150Y667467D01*
Y654345D01*
X444500Y646695D01*
Y644015D01*
X445835Y642680D01*
X459141D01*
X460653Y644192D01*
X467970D01*
X468514Y643648D01*
X469692D01*
X475820Y637520D01*
Y635422D01*
G01X476320Y629280D02*
X470960Y634640D01*
Y638844D01*
X469944Y639860D01*
X468073D01*
X465869Y637656D01*
X462016D01*
X461160Y636800D01*
X445700D01*
X441800Y640700D01*
Y656359D01*
X445270Y659829D01*
Y660832D01*
G01X600736Y668425D02*
X580486D01*
X567301Y655240D01*
X563125D01*
X562115Y654230D01*
Y651002D01*
X550690Y639577D01*
X515210D01*
X512630Y636997D01*
X483508D01*
X480006Y640499D01*
X479590D01*
X478580Y641509D01*
Y641925D01*
X473653Y646852D01*
X469426D01*
X467070Y649208D01*
X459708D01*
X459700Y649200D01*
X459000D01*
X454875Y645075D01*
X446500D01*
G01X463178Y647483D02*
X466739D01*
X468820Y645402D01*
X468921D01*
X469225Y645098D01*
X470859D01*
X480643Y635314D01*
X505986D01*
X508800Y632500D01*
X513800D01*
X517688Y636388D01*
X520550D01*
X521309Y635629D01*
X540969D01*
X542680Y637340D01*
X547660D01*
X549600Y635400D01*
X552200D01*
X552760Y635960D01*
Y638393D01*
X581067Y666700D01*
X601451D01*
X602461Y667710D01*
Y671027D01*
X602332Y671156D01*
G01X468540Y655799D02*
X468790Y656049D01*
X480017D01*
X480530Y656562D01*
X481970D01*
X482483Y656049D01*
X498569D01*
X501924Y652694D01*
X511629D01*
X516189Y657254D01*
X534801D01*
X536557Y655498D01*
G01X468260Y664366D02*
X469810Y665916D01*
Y669950D01*
X478639Y678779D01*
X480070D01*
X480946Y677903D01*
X491882D01*
X495357Y681378D01*
X497893D01*
X502120Y685605D01*
Y686464D01*
X505304Y689648D01*
X507124D01*
X508633Y691157D01*
X514106D01*
X514710Y690553D01*
X516144D01*
X518244Y692653D01*
X546909D01*
X551283Y697027D01*
Y699243D01*
G01X469467Y679915D02*
X476643Y687091D01*
X481942D01*
X483251Y685782D01*
X494876D01*
X504647Y695553D01*
X538669D01*
X544260Y701144D01*
X548686D01*
X553060Y705518D01*
X573976D01*
X575727Y703767D01*
X585890D01*
X587654Y705531D01*
X600856D01*
X603419Y708094D01*
X608975D01*
G01X612914Y707630D02*
X611653Y706369D01*
X603745D01*
X598942Y701566D01*
X575163D01*
X572661Y704068D01*
X553668D01*
X549071Y699471D01*
Y696866D01*
X546308Y694103D01*
X506699D01*
X500219Y687623D01*
Y685755D01*
X497292Y682828D01*
X495862D01*
X494618Y684072D01*
X491288D01*
X490857Y683641D01*
X480519D01*
X480130Y684030D01*
X477511D01*
X469977Y676496D01*
G01X487030Y68075D02*
X526329D01*
X531104Y63300D01*
X616500D01*
X634420Y81220D01*
Y186887D01*
X645169Y197636D01*
Y263669D01*
X705595Y324095D01*
Y422001D01*
X682764Y444832D01*
G01X721290Y484381D02*
X726122D01*
X743126Y467377D01*
Y353026D01*
X651020Y260920D01*
Y194715D01*
X643150Y186845D01*
Y81550D01*
X618100Y56500D01*
X504000D01*
X502900Y57600D01*
Y57670D01*
G01X501331Y528932D02*
X502583Y527680D01*
X511895D01*
X517474Y522101D01*
X586460D01*
X587568Y520993D01*
X632662D01*
X633815Y519840D01*
X636282D01*
X641118Y515005D01*
X644422D01*
X646460Y512967D01*
G01X725730Y486788D02*
X726473D01*
X745076Y468185D01*
Y352076D01*
X653040Y260040D01*
Y193597D01*
X645310Y185867D01*
Y80810D01*
X618500Y54000D01*
X529977D01*
X514780Y38803D01*
G01X513120Y72069D02*
X514608Y73557D01*
X619785D01*
X631800Y85572D01*
Y188502D01*
X643069Y199771D01*
Y264569D01*
X703495Y324995D01*
Y414100D01*
X672015Y445580D01*
Y457041D01*
X672190Y457216D01*
G01X657570Y730414D02*
X637786D01*
X636200Y732000D01*
X630000D01*
X629000Y733000D01*
X580800D01*
X579800Y732000D01*
X574300D01*
X571900Y734400D01*
X570600D01*
X568200Y732000D01*
X533835D01*
X522586Y720751D01*
X521183D01*
X517443Y717011D01*
G01X658860Y727383D02*
X656723D01*
X656140Y726800D01*
X631000D01*
X626700Y731100D01*
X581500D01*
X580100Y729700D01*
X540338D01*
X529739Y719101D01*
X525673D01*
X517775Y711203D01*
G01X522865Y711178D02*
Y711100D01*
X524200D01*
X541100Y728000D01*
X581400D01*
X582700Y729300D01*
X626000D01*
X630400Y724900D01*
X653200D01*
X656300Y721800D01*
X658854D01*
X659200Y721454D01*
G01X514498Y716473D02*
X515710Y717685D01*
Y717718D01*
X521640Y723648D01*
Y724846D01*
X528216Y731422D01*
Y732769D01*
X533055Y737608D01*
X636592D01*
X637400Y736800D01*
X639654D01*
X643300Y733154D01*
X649114D01*
X650460Y734500D01*
X654500D01*
X656000Y733000D01*
Y732400D01*
G01X729640Y486848D02*
X750448Y466040D01*
Y355048D01*
X663420Y268020D01*
Y222525D01*
X655090Y214195D01*
Y193208D01*
X647170Y185288D01*
Y80270D01*
X618900Y52000D01*
X547977D01*
X534780Y38803D01*
G01X553193Y724847D02*
X552346Y724000D01*
Y721274D01*
X550167Y719095D01*
X543466D01*
X535588Y711217D01*
X535272D01*
G01X732817Y489435D02*
X741552Y480700D01*
X744079D01*
X760219Y464560D01*
Y359919D01*
X666720Y266420D01*
Y219464D01*
X662750Y215494D01*
Y201840D01*
X659010Y198100D01*
Y191844D01*
X650870Y183704D01*
Y79070D01*
X620400Y48600D01*
X564577D01*
X554780Y38803D01*
G01X720150Y491632D02*
X727296D01*
X752098Y466830D01*
Y354298D01*
X665070Y267270D01*
Y221827D01*
X657150Y213907D01*
Y192621D01*
X648930Y184401D01*
Y79530D01*
X619700Y50300D01*
X556277D01*
X544780Y38803D01*
G01X646600Y463571D02*
Y463576D01*
X633030Y477146D01*
X603250D01*
X587486Y492910D01*
X545150D01*
X543280Y491040D01*
G01X546250Y490302D02*
Y490306D01*
X547020Y491076D01*
X586726D01*
X602490Y475312D01*
X627305D01*
X632680Y469937D01*
Y466669D01*
G01X570614Y713237D02*
X577442D01*
X579963Y715758D01*
X591649D01*
X593229Y717338D01*
X604839D01*
X605167Y717666D01*
X611288D01*
X613010Y719388D01*
X614450D01*
X614725Y719113D01*
X618212D01*
X619590Y720491D01*
X639857D01*
X642097Y722731D01*
X645790D01*
X655456Y713065D01*
X656642D01*
X656650Y713057D01*
G01X644950Y719110D02*
X644819Y719241D01*
X620115D01*
X616812Y715938D01*
X613015D01*
X612537Y716416D01*
X605688D01*
X602614Y713342D01*
X589439D01*
X588890Y713891D01*
X580690D01*
X575478Y708679D01*
X565062D01*
G01X759400Y334839D02*
X758305Y335934D01*
Y337426D01*
X756215Y339516D01*
X742216D01*
X668420Y265720D01*
Y218032D01*
X667260Y216872D01*
Y202015D01*
X661155Y195910D01*
Y191647D01*
X652850Y183342D01*
Y78650D01*
X621100Y46900D01*
X585468D01*
X577371Y38803D01*
G01X583930Y652439D02*
Y649695D01*
X576898Y642663D01*
Y622090D01*
X577000Y621988D01*
Y620029D01*
G01X601856Y711479D02*
X589246D01*
X588284Y712441D01*
X581295D01*
X576442Y707588D01*
Y705492D01*
G01X606146Y713145D02*
X602635Y709634D01*
X599491D01*
X596865Y707008D01*
X595435D01*
X592809Y709634D01*
X585394D01*
X584312Y710716D01*
G01X754850Y335055D02*
X740155D01*
X671140Y266040D01*
Y195260D01*
X661160Y185280D01*
Y143428D01*
X654500Y136768D01*
Y77900D01*
X621800Y45200D01*
X603768D01*
X597371Y38803D01*
G01X597440Y391690D02*
X603848Y398098D01*
Y419698D01*
X616231Y432081D01*
X652752D01*
X667920Y447249D01*
Y457409D01*
X674353Y463842D01*
G01X598670Y508170D02*
X603552Y503288D01*
X660165D01*
X662630Y500823D01*
G01X645150Y535704D02*
X656980D01*
X666326Y545050D01*
X698058D01*
X703600Y539508D01*
Y532026D01*
X711566Y524060D01*
X713469D01*
X730575Y506954D01*
Y503925D01*
X761869Y472631D01*
Y333669D01*
X759880Y331680D01*
X741680D01*
X674760Y264760D01*
Y186651D01*
X664980Y176871D01*
Y142118D01*
X658290Y135428D01*
Y76590D01*
X620500Y38800D01*
X617371D01*
Y38803D01*
G01X755500Y337791D02*
X756575Y336716D01*
Y334340D01*
X755565Y333330D01*
X740930D01*
X672900Y265300D01*
Y187729D01*
X663020Y177849D01*
Y142612D01*
X656580Y136172D01*
Y77580D01*
X622400Y43400D01*
X611968D01*
X607371Y38803D01*
G01X739968Y29361D02*
X727590Y16983D01*
X702118D01*
X699936Y19165D01*
Y45775D01*
X708105Y53944D01*
Y103974D01*
X706405Y105674D01*
Y117447D01*
X689423Y134429D01*
Y186248D01*
X691590Y188415D01*
Y207696D01*
X693415Y209521D01*
Y212935D01*
X690245Y216105D01*
Y221833D01*
X693600Y225188D01*
Y271566D01*
X743562Y321528D01*
X755598D01*
X763519Y329449D01*
Y473766D01*
X747892Y489393D01*
Y492608D01*
X745857Y494643D01*
X742642D01*
X735630Y501655D01*
Y505107D01*
X717985Y522752D01*
Y527457D01*
X698742Y546700D01*
X637801D01*
X628167Y537066D01*
X616320D01*
G01X639963Y38803D02*
Y44463D01*
X660081Y64581D01*
Y133908D01*
X666731Y140558D01*
Y175435D01*
X678315Y187019D01*
Y198608D01*
X676925Y199998D01*
Y264425D01*
X741475Y328975D01*
X752517D01*
X753230Y328262D01*
G01X639350Y250123D02*
Y262950D01*
X701770Y325370D01*
Y331938D01*
G01X669963Y38803D02*
X666000Y42766D01*
Y135047D01*
X670110Y139157D01*
Y172609D01*
X685515Y188014D01*
Y268215D01*
X742552Y325252D01*
X749219D01*
X750700Y323771D01*
G01X745220Y327250D02*
X742150D01*
X683865Y268965D01*
Y189402D01*
X668460Y173997D01*
Y139841D01*
X664222Y135603D01*
Y43062D01*
X659963Y38803D01*
G01X747600Y323527D02*
X743227D01*
X691950Y272250D01*
Y227603D01*
X687165Y222818D01*
Y186636D01*
X671760Y171231D01*
Y138473D01*
X667800Y134513D01*
Y50966D01*
X679963Y38803D01*
G01X703661Y20708D02*
X704470Y21517D01*
Y43055D01*
X708901Y47486D01*
Y52169D01*
X709855Y53123D01*
Y115483D01*
X693180Y132157D01*
Y184276D01*
X691795Y185661D01*
Y187091D01*
X694650Y189946D01*
Y204391D01*
X695265Y205006D01*
Y271746D01*
X743720Y320201D01*
X755756D01*
X765250Y329695D01*
Y357789D01*
G01X738130Y502748D02*
X739752D01*
X768025Y474475D01*
Y329500D01*
X756626Y318101D01*
X744590D01*
X699222Y272733D01*
Y208382D01*
X700575Y207029D01*
Y180604D01*
X696425Y176454D01*
Y132407D01*
X711955Y116877D01*
Y51298D01*
X711676Y51019D01*
G01X765610Y361194D02*
X766975Y359829D01*
Y329935D01*
X756191Y319151D01*
X744155D01*
X698172Y273168D01*
Y207947D01*
X699525Y206594D01*
Y205164D01*
X695700Y201339D01*
Y182346D01*
X695375Y182021D01*
Y131967D01*
X710905Y116437D01*
Y52688D01*
X709951Y51734D01*
Y34769D01*
X719800Y24920D01*
G54D12*
X154038Y511386D03*
X153967Y517186D03*
X162335Y528206D03*
X159186Y534504D03*
X154945Y539233D03*
X159185Y547103D03*
X154900Y548682D03*
X159186Y553402D03*
X157611Y557468D03*
X154410Y557990D03*
X178117Y528187D03*
X173217Y536556D03*
X187417Y508756D03*
X189007Y514846D03*
X187875Y534128D03*
X184384Y543955D03*
X188927Y537836D03*
X190434Y546870D03*
X181491Y557436D03*
X230476Y508891D03*
X239925Y518339D03*
Y534087D03*
Y521489D03*
Y537236D03*
X231209Y566282D03*
X249374Y512040D03*
X246224D03*
X249374Y549835D03*
X249344Y552984D03*
Y556134D03*
X246224Y559284D03*
Y556134D03*
Y562434D03*
X265122Y512040D03*
X261972D03*
X265122Y549836D03*
X261972D03*
X277725Y521493D03*
X674353Y463842D03*
X683112Y483723D03*
X710671Y479786D03*
G54D13*
X514780Y38803D03*
X534780D03*
X544780D03*
X554780D03*
X577371D03*
X597371D03*
X607371D03*
X617371D03*
X639963D03*
X659963D03*
X669963D03*
X679963D03*
G54D14*
X590999Y92789D03*
X615657D03*
G54D15*
X703661Y20708D03*
G54D16*
X739968Y29361D03*
G54D17*
G01X28250Y438740D02*
Y381346D01*
X49244Y360352D01*
G01X57624Y366105D02*
X37990Y385739D01*
Y453022D01*
G01X28250Y472076D02*
Y438740D01*
G01X37990Y453022D02*
Y520218D01*
G01X28250Y472076D02*
Y528146D01*
X36240Y536136D01*
Y537993D01*
X38807Y540560D01*
Y543539D01*
G01X72216Y540493D02*
X66873Y535150D01*
X52922D01*
X37990Y520218D01*
G01X49244Y360352D02*
X64450Y345146D01*
Y315053D01*
X82368Y297135D01*
G01X66262Y553344D02*
X60580Y547662D01*
X42930D01*
X38807Y543539D01*
G01X72150Y225148D02*
X64570Y217568D01*
Y176257D01*
X68756Y172071D01*
Y167695D01*
G01D02*
X68750Y167689D01*
Y165019D01*
X68100Y164369D01*
Y162711D01*
X69271Y161540D01*
X75858D01*
X78800Y164482D01*
Y170375D01*
X81030Y172605D01*
G01X93200Y300734D02*
X81230Y312704D01*
Y342499D01*
X57624Y366105D01*
G01X125340Y558104D02*
X122087Y554851D01*
X67769D01*
X66262Y553344D01*
G01X82030Y191733D02*
X78800Y188503D01*
Y174835D01*
X81030Y172605D01*
G01X82030Y191733D02*
Y201405D01*
X83579Y202954D01*
Y214273D01*
X85876Y216570D01*
Y218939D01*
G01X78614Y229920D02*
X78620D01*
Y232271D01*
X79210Y232861D01*
X79217D01*
G01X72150Y225148D02*
X73842D01*
X78614Y229920D01*
G01X82368Y297135D02*
X82370D01*
X84940Y294565D01*
Y257258D01*
X81370Y253688D01*
Y235014D01*
X79217Y232861D01*
G01X132960Y550005D02*
X129580Y546625D01*
X78348D01*
X72216Y540493D01*
G01X85876Y218939D02*
X95520Y228583D01*
X95528D01*
X96168Y229223D01*
Y231618D01*
G01D02*
X96160D01*
X94890Y232888D01*
Y237886D01*
X93200Y239576D01*
Y300734D01*
G01X158430Y568437D02*
X158296Y568303D01*
X151258D01*
X132960Y550005D01*
G01X125340Y558090D02*
Y558104D01*
G01D02*
X143237Y576001D01*
X145020D01*
G01D02*
X146670Y577651D01*
X150900D01*
X153064Y579815D01*
X156516D01*
X164600Y587899D01*
Y588689D01*
X165770Y589860D01*
X166561D01*
X166605Y589904D01*
X182156D01*
X184541Y587519D01*
X213180D01*
X220428Y580271D01*
G01X188654Y573395D02*
X186849Y575200D01*
X176600D01*
X174250Y572850D01*
X173750D01*
X172700Y571800D01*
X161793D01*
X158430Y568437D01*
G01X188654Y573395D02*
X189215Y573956D01*
X193069D01*
X196175Y570850D01*
X216590D01*
G01X249344Y556134D02*
Y558524D01*
X250260Y559440D01*
Y563245D01*
X235418Y578087D01*
X223453D01*
G01X216590Y570850D02*
X218500Y568940D01*
X228551D01*
X231209Y566282D01*
G01X223453Y578087D02*
X222610D01*
X222530Y578167D01*
Y578169D01*
X220428Y580271D01*
G01X231209Y566282D02*
Y566217D01*
X242486Y554940D01*
X244238D01*
X246194Y552984D01*
X249344D01*
G01D02*
Y556134D01*
G01X323931Y589733D02*
Y586824D01*
X316975Y579868D01*
X288258D01*
X285570Y582556D01*
X268158D01*
X260060Y590654D01*
Y602993D01*
G01D02*
X260064D01*
G01X451325Y525981D02*
Y524875D01*
X454158Y522042D01*
X455891D01*
X458656Y524807D01*
X467324D01*
X474459Y517672D01*
Y468339D01*
X471362Y465242D01*
X430675D01*
X428747Y463314D01*
G01X449402Y515514D02*
Y516833D01*
X453011Y520442D01*
X456554D01*
X459319Y523207D01*
X466661D01*
X472859Y517009D01*
Y469002D01*
X470699Y466842D01*
X430675D01*
X428747Y468770D01*
G54D18*
G01X755157Y312969D02*
X761055D01*
X772700Y324614D01*
Y484443D01*
X714540Y542603D01*
X707125D01*
X699247Y550481D01*
X621449D01*
X618340Y553590D01*
Y563925D01*
X610862Y571403D01*
X595080D01*
X589869Y576614D01*
Y587251D01*
X587819Y589301D01*
X582432D01*
X563594Y608139D01*
X525744D01*
X525250Y607645D01*
X521598D01*
X515508Y601555D01*
X512608D01*
X509738Y604425D01*
X433856D01*
X432970Y603539D01*
X425473D01*
X420584Y598650D01*
X409195D01*
G54D19*
G01X227890Y516769D02*
X239047D01*
G01X227890Y519919D02*
X239047D01*
G01X227890Y523069D02*
X239047D01*
G01X227890Y526219D02*
X241094D01*
G01X227890Y535667D02*
X239047D01*
G01X227890Y538817D02*
X239047D01*
G01X227890Y541967D02*
X241094D01*
M02*
